FILE_TYPE = MACRO_DRAWING;
SET COLOR_WIRE YELLOW;
SET COLOR_PROP ORANGE;
SET COLOR_DOT WHITE;
SET COLOR_ARC YELLOW;
SET COLOR_BODY GREEN;
SET COLOR_NOTE PURPLE;
SET PROP_DISPLAY VALUE;
SET PAGE_NUMBER P168;
FORCEADD MOSFET_N..1
(-7825 1525);
FORCEPROP 1 LAST LOCATION PQ17
J 0
(-7700 1525);
DISPLAY 0.489362 (-7700 1525);
PAINT SKYBLUE (-7700 1525);
FORCEPROP 0 LAST $SEC 1
J 0
(-7700 1550);
DISPLAY 0.680851 (-7700 1550);
PAINT MONO (-7700 1550);
DISPLAY INVISIBLE (-7700 1550);
FORCEPROP 0 LAST CDS_SEC 1
J 0
(-7700 1550);
DISPLAY 1.021277 (-7700 1550);
DISPLAY INVISIBLE (-7700 1550);
FORCEPROP 1 LASTPIN (-7775 1625) $PN D
R 1
J 0
(-7775 1618);
DISPLAY 0.489362 (-7775 1618);
PAINT MONO (-7775 1618);
FORCEPROP 1 LASTPIN (-7925 1425) $PN G
J 2
(-7915 1428);
DISPLAY 0.489362 (-7915 1428);
PAINT MONO (-7915 1428);
FORCEPROP 1 LASTPIN (-7775 1325) $PN S
R 1
J 2
(-7775 1338);
DISPLAY 0.489362 (-7775 1338);
PAINT MONO (-7775 1338);
FORCEPROP 1 LAST MATERIAL IC
J 0
(-7700 1375);
DISPLAY 0.489362 (-7700 1375);
PAINT SKYBLUE (-7700 1375);
FORCEPROP 1 LAST VALUE BSS138K
J 0
(-7700 1475);
DISPLAY 0.489362 (-7700 1475);
PAINT SKYBLUE (-7700 1475);
FORCEPROP 1 LAST PART_NUMBER BAM138K0000
J 0
(-7700 1425);
DISPLAY 0.489362 (-7700 1425);
PAINT SKYBLUE (-7700 1425);
FORCEPROP 0 LAST MANUF_PN BSS138K
J 0
(-7725 1325);
DISPLAY 1.021277 (-7725 1325);
DISPLAY INVISIBLE (-7725 1325);
FORCEPROP 2 LAST CDS_LIB pure_quanta
J 0
(-7825 1525);
DISPLAY INVISIBLE (-7825 1525);
FORCEPROP 1 LAST CDS_LMAN_SYM_OUTLINE -50,50,100,-150
J 0
(-7825 1525);
DISPLAY 0.468085 (-7825 1525);
PAINT GREEN (-7825 1525);
DISPLAY INVISIBLE (-7825 1525);
FORCEPROP 0 LAST PATH I1
J 0
(-7650 1350);
DISPLAY 1.021277 (-7650 1350);
DISPLAY INVISIBLE (-7650 1350);
FORCEPROP 1 LAST PACK_TYPE SMLF
J 0
(-7800 1275);
DISPLAY 0.723404 (-7800 1275);
PAINT SKYBLUE (-7800 1275);
DISPLAY INVISIBLE (-7800 1275);
FORCEADD UNIVERSAL_GND..1
(-2900 5875);
FORCEPROP 3 LASTPIN (-2900 5925) SIG_NAME GND\g
J 0
(-2890 5935);
DISPLAY 0.659574 (-2890 5935);
PAINT MONO (-2890 5935);
DISPLAY INVISIBLE (-2890 5935);
FORCEPROP 2 LAST CDS_LIB pure_quanta_power
J 0
(-2900 5875);
DISPLAY INVISIBLE (-2900 5875);
FORCEPROP 1 LAST PATH I10
J 0
(-2825 5875);
DISPLAY 0.872340 (-2825 5875);
PAINT AQUA (-2825 5875);
DISPLAY INVISIBLE (-2825 5875);
FORCEPROP 1 LAST HDL_POWER GND
J 1
(-2875 5800);
DISPLAY 0.872340 (-2875 5800);
PAINT GREEN (-2875 5800);
DISPLAY INVISIBLE (-2875 5800);
FORCEADD Q_CAP..1
(-5300 475);
FORCEPROP 1 LAST LOCATION PC7
J 0
(-5250 575);
DISPLAY 0.489362 (-5250 575);
PAINT SKYBLUE (-5250 575);
FORCEPROP 2 LAST SEC 1
J 0
(-5250 675);
DISPLAY 0.680851 (-5250 675);
PAINT MONO (-5250 675);
DISPLAY INVISIBLE (-5250 675);
FORCEPROP 1 LASTPIN (-5300 575) $PN 1
J 0
(-5290 555);
DISPLAY 0.489362 (-5290 555);
PAINT MONO (-5290 555);
FORCEPROP 1 LASTPIN (-5300 375) $PN 2
J 0
(-5290 355);
DISPLAY 0.489362 (-5290 355);
PAINT MONO (-5290 355);
FORCEPROP 1 LAST PART_NUMBER CH4104K1B00
J 0
(-5250 325);
DISPLAY 0.489362 (-5250 325);
PAINT SKYBLUE (-5250 325);
FORCEPROP 1 LAST MATERIAL X7R
J 0
(-5250 375);
DISPLAY 0.489362 (-5250 375);
PAINT SKYBLUE (-5250 375);
FORCEPROP 1 LAST TOLERANCE 10%
J 0
(-5250 425);
DISPLAY 0.489362 (-5250 425);
PAINT SKYBLUE (-5250 425);
FORCEPROP 1 LAST VALUE 0.1UF
J 0
(-5250 525);
DISPLAY 0.489362 (-5250 525);
PAINT SKYBLUE (-5250 525);
FORCEPROP 1 LAST VOLTAGE 25V
J 0
(-5250 475);
DISPLAY 0.489362 (-5250 475);
PAINT SKYBLUE (-5250 475);
FORCEPROP 1 LAST PACK_TYPE 0402
J 0
(-5250 275);
DISPLAY 0.489362 (-5250 275);
PAINT SKYBLUE (-5250 275);
FORCEPROP 2 LAST CDS_LIB pure_quanta
J 0
(-5300 475);
DISPLAY INVISIBLE (-5300 475);
FORCEPROP 2 LAST SEC_TYPE 0402
J 0
(-5250 675);
DISPLAY 1.021277 (-5250 675);
DISPLAY INVISIBLE (-5250 675);
FORCEPROP 1 LAST PATH I100
J 0
(-5250 625);
DISPLAY 0.978723 (-5250 625);
PAINT WHITE (-5250 625);
DISPLAY INVISIBLE (-5250 625);
FORCEADD Q_RES..1
(-5975 650);
FORCEPROP 1 LAST LOCATION PR314
J 0
(-6000 700);
DISPLAY 0.489362 (-6000 700);
PAINT SKYBLUE (-6000 700);
FORCEPROP 0 LAST $SEC 1
J 0
(-6025 750);
DISPLAY 0.680851 (-6025 750);
PAINT MONO (-6025 750);
DISPLAY INVISIBLE (-6025 750);
FORCEPROP 0 LAST CDS_SEC 1
J 0
(-6025 750);
DISPLAY 1.021277 (-6025 750);
DISPLAY INVISIBLE (-6025 750);
FORCEPROP 1 LASTPIN (-6075 650) $PN 1
J 0
(-6063 662);
DISPLAY 0.489362 (-6063 662);
PAINT MONO (-6063 662);
FORCEPROP 1 LASTPIN (-5875 650) $PN 2
J 0
(-5913 662);
DISPLAY 0.489362 (-5913 662);
PAINT MONO (-5913 662);
FORCEPROP 1 LAST MATERIAL CHIP
J 0
(-6225 575);
DISPLAY 0.489362 (-6225 575);
PAINT SKYBLUE (-6225 575);
FORCEPROP 1 LAST PART_NUMBER CS00002JB38
J 0
(-6225 600);
DISPLAY 0.489362 (-6225 600);
PAINT SKYBLUE (-6225 600);
FORCEPROP 1 LAST PACK_TYPE 0402LF
J 0
(-5875 575);
DISPLAY 0.489362 (-5875 575);
PAINT SKYBLUE (-5875 575);
FORCEPROP 1 LAST WATTAGE 1/16W
J 0
(-5875 600);
DISPLAY 0.489362 (-5875 600);
PAINT SKYBLUE (-5875 600);
FORCEPROP 1 LAST TOLERANCE 5%
J 0
(-5850 675);
DISPLAY 0.489362 (-5850 675);
PAINT SKYBLUE (-5850 675);
FORCEPROP 1 LAST VALUE 0
J 2
(-6100 675);
DISPLAY 0.489362 (-6100 675);
PAINT SKYBLUE (-6100 675);
FORCEPROP 2 LAST CDS_LIB pure_quanta
J 0
(-5975 650);
DISPLAY INVISIBLE (-5975 650);
FORCEPROP 1 LAST PATH I101
J 0
(-6025 800);
DISPLAY 0.978723 (-6025 800);
PAINT WHITE (-6025 800);
DISPLAY INVISIBLE (-6025 800);
FORCEADD UNIVERSAL_GND..1
(-5300 250);
FORCEPROP 3 LASTPIN (-5300 300) SIG_NAME GND\g
J 0
(-5290 310);
DISPLAY 0.659574 (-5290 310);
PAINT MONO (-5290 310);
DISPLAY INVISIBLE (-5290 310);
FORCEPROP 2 LAST CDS_LIB pure_quanta_power
J 0
(-5300 250);
DISPLAY INVISIBLE (-5300 250);
FORCEPROP 1 LAST PATH I102
J 0
(-5225 250);
DISPLAY 0.872340 (-5225 250);
PAINT AQUA (-5225 250);
DISPLAY INVISIBLE (-5225 250);
FORCEPROP 1 LAST HDL_POWER GND
J 1
(-5275 175);
DISPLAY 0.872340 (-5275 175);
PAINT GREEN (-5275 175);
DISPLAY INVISIBLE (-5275 175);
FORCEADD VCC_CORE..1
(-6175 725);
FORCEPROP 3 LASTPIN (-6175 675) SIG_NAME P12V_STBY\g
J 0
(-6165 685);
DISPLAY 0.659574 (-6165 685);
PAINT MONO (-6165 685);
DISPLAY INVISIBLE (-6165 685);
FORCEPROP 1 LAST HDL_POWER P12V_STBY
J 1
(-6175 775);
DISPLAY 0.489362 (-6175 775);
PAINT GREEN (-6175 775);
FORCEPROP 2 LAST CDS_LIB pure_quanta_power
J 0
(-6175 725);
DISPLAY INVISIBLE (-6175 725);
FORCEPROP 1 LAST PATH I103
J 0
(-6125 750);
DISPLAY 0.872340 (-6125 750);
PAINT AQUA (-6125 750);
DISPLAY INVISIBLE (-6125 750);
FORCEADD Q_RES..1
(-7250 825);
FORCEPROP 1 LAST LOCATION PR290
J 0
(-7300 875);
DISPLAY 0.489362 (-7300 875);
PAINT SKYBLUE (-7300 875);
FORCEPROP 0 LAST $SEC 1
J 0
(-7300 925);
DISPLAY 0.680851 (-7300 925);
PAINT MONO (-7300 925);
DISPLAY INVISIBLE (-7300 925);
FORCEPROP 0 LAST CDS_SEC 1
J 0
(-7300 925);
DISPLAY 1.021277 (-7300 925);
DISPLAY INVISIBLE (-7300 925);
FORCEPROP 1 LASTPIN (-7350 825) $PN 1
J 0
(-7338 837);
DISPLAY 0.489362 (-7338 837);
PAINT MONO (-7338 837);
FORCEPROP 1 LASTPIN (-7150 825) $PN 2
J 0
(-7188 837);
DISPLAY 0.489362 (-7188 837);
PAINT MONO (-7188 837);
FORCEPROP 1 LAST VALUE 40.2K
J 2
(-7400 850);
DISPLAY 0.489362 (-7400 850);
PAINT SKYBLUE (-7400 850);
FORCEPROP 1 LAST PART_NUMBER TMP_QCS34022FB15
J 0
(-7550 775);
DISPLAY 0.489362 (-7550 775);
PAINT SKYBLUE (-7550 775);
FORCEPROP 1 LAST WATTAGE 1/16W
J 0
(-7125 775);
DISPLAY 0.489362 (-7125 775);
PAINT SKYBLUE (-7125 775);
FORCEPROP 1 LAST MATERIAL CHIP
J 0
(-7550 750);
DISPLAY 0.489362 (-7550 750);
PAINT SKYBLUE (-7550 750);
FORCEPROP 1 LAST TOLERANCE 1%
J 0
(-7100 850);
DISPLAY 0.489362 (-7100 850);
PAINT SKYBLUE (-7100 850);
FORCEPROP 1 LAST PACK_TYPE 0402LF
J 0
(-7125 750);
DISPLAY 0.489362 (-7125 750);
PAINT SKYBLUE (-7125 750);
FORCEPROP 2 LAST CDS_LIB pure_quanta
J 0
(-7250 825);
DISPLAY INVISIBLE (-7250 825);
FORCEPROP 1 LAST PATH I104
J 0
(-7300 975);
DISPLAY 0.978723 (-7300 975);
PAINT WHITE (-7300 975);
DISPLAY INVISIBLE (-7300 975);
FORCEADD Q_RES..2
(-6950 625);
FORCEPROP 1 LAST LOCATION PR5
J 0
(-6900 725);
DISPLAY 0.489362 (-6900 725);
PAINT SKYBLUE (-6900 725);
FORCEPROP 2 LAST SEC 1
J 0
(-6900 850);
DISPLAY 0.680851 (-6900 850);
PAINT MONO (-6900 850);
DISPLAY INVISIBLE (-6900 850);
FORCEPROP 1 LASTPIN (-6950 725) $PN 1
J 0
(-6945 687);
DISPLAY 0.489362 (-6945 687);
PAINT MONO (-6945 687);
FORCEPROP 1 LASTPIN (-6950 525) $PN 2
J 0
(-6945 535);
DISPLAY 0.489362 (-6945 535);
PAINT MONO (-6945 535);
FORCEPROP 1 LAST MATERIAL CHIP
J 0
(-6900 525);
DISPLAY 0.489362 (-6900 525);
PAINT SKYBLUE (-6900 525);
FORCEPROP 1 LAST PART_NUMBER TMP_QCS31002FB26
J 0
(-6900 475);
DISPLAY 0.489362 (-6900 475);
PAINT SKYBLUE (-6900 475);
FORCEPROP 1 LAST WATTAGE 1/16W
J 0
(-6900 575);
DISPLAY 0.489362 (-6900 575);
PAINT SKYBLUE (-6900 575);
FORCEPROP 1 LAST TOLERANCE 1%
J 0
(-6900 625);
DISPLAY 0.489362 (-6900 625);
PAINT SKYBLUE (-6900 625);
FORCEPROP 1 LAST VALUE 10K
J 0
(-6900 675);
DISPLAY 0.489362 (-6900 675);
PAINT SKYBLUE (-6900 675);
FORCEPROP 1 LAST PACK_TYPE 0402LF
J 0
(-6900 425);
DISPLAY 0.489362 (-6900 425);
PAINT SKYBLUE (-6900 425);
FORCEPROP 2 LAST SEC_TYPE 0402LF
J 0
(-6900 850);
DISPLAY 1.021277 (-6900 850);
DISPLAY INVISIBLE (-6900 850);
FORCEPROP 2 LAST CDS_LIB pure_quanta
J 0
(-6950 625);
DISPLAY INVISIBLE (-6950 625);
FORCEPROP 1 LAST PATH I105
J 0
(-6900 800);
DISPLAY 0.978723 (-6900 800);
PAINT WHITE (-6900 800);
DISPLAY INVISIBLE (-6900 800);
FORCEADD UNIVERSAL_GND..1
(-6950 400);
FORCEPROP 3 LASTPIN (-6950 450) SIG_NAME GND\g
J 0
(-6940 460);
DISPLAY 0.659574 (-6940 460);
PAINT MONO (-6940 460);
DISPLAY INVISIBLE (-6940 460);
FORCEPROP 2 LAST CDS_LIB pure_quanta_power
J 0
(-6950 400);
DISPLAY INVISIBLE (-6950 400);
FORCEPROP 1 LAST PATH I107
J 0
(-6875 400);
DISPLAY 0.872340 (-6875 400);
PAINT AQUA (-6875 400);
DISPLAY INVISIBLE (-6875 400);
FORCEPROP 1 LAST HDL_POWER GND
J 1
(-6925 325);
DISPLAY 0.872340 (-6925 325);
PAINT GREEN (-6925 325);
DISPLAY INVISIBLE (-6925 325);
FORCEADD UNIVERSAL_GND..1
(-6475 400);
FORCEPROP 3 LASTPIN (-6475 450) SIG_NAME GND\g
J 0
(-6465 460);
DISPLAY 0.659574 (-6465 460);
PAINT MONO (-6465 460);
DISPLAY INVISIBLE (-6465 460);
FORCEPROP 2 LAST CDS_LIB pure_quanta_power
J 0
(-6475 400);
DISPLAY INVISIBLE (-6475 400);
FORCEPROP 1 LAST PATH I108
J 0
(-6400 400);
DISPLAY 0.872340 (-6400 400);
PAINT AQUA (-6400 400);
DISPLAY INVISIBLE (-6400 400);
FORCEPROP 1 LAST HDL_POWER GND
J 1
(-6450 325);
DISPLAY 0.872340 (-6450 325);
PAINT GREEN (-6450 325);
DISPLAY INVISIBLE (-6450 325);
FORCEADD VCC_CORE..1
(-7550 950);
FORCEPROP 3 LASTPIN (-7550 900) SIG_NAME P5V_STBY\g
J 0
(-7540 910);
DISPLAY 0.659574 (-7540 910);
PAINT MONO (-7540 910);
DISPLAY INVISIBLE (-7540 910);
FORCEPROP 1 LAST HDL_POWER P5V_STBY
J 1
(-7550 1000);
DISPLAY 0.489362 (-7550 1000);
PAINT GREEN (-7550 1000);
FORCEPROP 2 LAST CDS_LIB pure_quanta_power
J 0
(-7550 950);
DISPLAY INVISIBLE (-7550 950);
FORCEPROP 1 LAST PATH I109
J 0
(-7500 975);
DISPLAY 0.872340 (-7500 975);
PAINT AQUA (-7500 975);
DISPLAY INVISIBLE (-7500 975);
FORCEADD OFFPAGE..2
R 2
(-7075 1000);
FORCEPROP 2 LAST $XR0 81 
J 0
(-7329 1000);
DISPLAY 0.638298 (-7329 1000);
PAINT MONO (-7329 1000);
FORCEPROP 2 LAST CDS_LIB standard
J 0
(-7075 1000);
DISPLAY INVISIBLE (-7075 1000);
FORCEPROP 1 LAST OFFPAGE TRUE
J 2
(-7400 875);
DISPLAY 0.872340 (-7400 875);
PAINT GREEN (-7400 875);
DISPLAY INVISIBLE (-7400 875);
FORCEPROP 1 LAST COMMENT_BODY TRUE
J 2
(-7030 905);
DISPLAY 0.872340 (-7030 905);
PAINT GREEN (-7030 905);
DISPLAY INVISIBLE (-7030 905);
FORCEPROP 2 LAST PATH I110
J 0
(-7025 1075);
DISPLAY 1.021277 (-7025 1075);
DISPLAY INVISIBLE (-7025 1075);
FORCEADD VCC_CORE..1
(-6600 1400);
FORCEPROP 3 LASTPIN (-6600 1350) SIG_NAME P3V3_STBY\g
J 0
(-6590 1360);
DISPLAY 0.659574 (-6590 1360);
PAINT MONO (-6590 1360);
DISPLAY INVISIBLE (-6590 1360);
FORCEPROP 1 LAST HDL_POWER P3V3_STBY
J 1
(-6600 1450);
DISPLAY 0.489362 (-6600 1450);
PAINT GREEN (-6600 1450);
FORCEPROP 2 LAST CDS_LIB pure_quanta_power
J 0
(-6600 1400);
DISPLAY INVISIBLE (-6600 1400);
FORCEPROP 1 LAST PATH I111
J 0
(-6550 1425);
DISPLAY 0.872340 (-6550 1425);
PAINT AQUA (-6550 1425);
DISPLAY INVISIBLE (-6550 1425);
FORCEADD Q_RES..1
(-6325 1250);
FORCEPROP 1 LAST LOCATION PR298
J 0
(-6375 1300);
DISPLAY 0.489362 (-6375 1300);
PAINT SKYBLUE (-6375 1300);
FORCEPROP 0 LAST $SEC 1
J 0
(-6375 1350);
DISPLAY 0.680851 (-6375 1350);
PAINT MONO (-6375 1350);
DISPLAY INVISIBLE (-6375 1350);
FORCEPROP 0 LAST CDS_SEC 1
J 0
(-6375 1350);
DISPLAY 1.021277 (-6375 1350);
DISPLAY INVISIBLE (-6375 1350);
FORCEPROP 1 LASTPIN (-6425 1250) $PN 1
J 0
(-6413 1262);
DISPLAY 0.489362 (-6413 1262);
PAINT MONO (-6413 1262);
FORCEPROP 1 LASTPIN (-6225 1250) $PN 2
J 0
(-6263 1262);
DISPLAY 0.489362 (-6263 1262);
PAINT MONO (-6263 1262);
FORCEPROP 1 LAST WATTAGE 1/16W
J 0
(-6225 1200);
DISPLAY 0.489362 (-6225 1200);
PAINT SKYBLUE (-6225 1200);
FORCEPROP 1 LAST MATERIAL CHIP
J 0
(-6650 1150);
DISPLAY 0.489362 (-6650 1150);
PAINT SKYBLUE (-6650 1150);
FORCEPROP 1 LAST TOLERANCE 1%
J 0
(-6225 1275);
DISPLAY 0.489362 (-6225 1275);
PAINT SKYBLUE (-6225 1275);
FORCEPROP 1 LAST VALUE 1K
J 2
(-6475 1275);
DISPLAY 0.489362 (-6475 1275);
PAINT SKYBLUE (-6475 1275);
FORCEPROP 1 LAST PART_NUMBER TMP_QCS21002FB24
J 0
(-6650 1200);
DISPLAY 0.489362 (-6650 1200);
PAINT SKYBLUE (-6650 1200);
FORCEPROP 1 LAST PACK_TYPE 0402LF
J 0
(-6225 1150);
DISPLAY 0.489362 (-6225 1150);
PAINT SKYBLUE (-6225 1150);
FORCEPROP 2 LAST CDS_LIB pure_quanta
J 0
(-6325 1250);
DISPLAY INVISIBLE (-6325 1250);
FORCEPROP 1 LAST PATH I112
J 0
(-6375 1400);
DISPLAY 0.978723 (-6375 1400);
PAINT WHITE (-6375 1400);
DISPLAY INVISIBLE (-6375 1400);
FORCEADD Q_RES..1
(-6325 1000);
FORCEPROP 1 LAST LOCATION PR299
J 0
(-6375 1050);
DISPLAY 0.489362 (-6375 1050);
PAINT SKYBLUE (-6375 1050);
FORCEPROP 0 LAST $SEC 1
J 0
(-6375 1100);
DISPLAY 0.680851 (-6375 1100);
PAINT MONO (-6375 1100);
DISPLAY INVISIBLE (-6375 1100);
FORCEPROP 0 LAST CDS_SEC 1
J 0
(-6375 1100);
DISPLAY 1.021277 (-6375 1100);
DISPLAY INVISIBLE (-6375 1100);
FORCEPROP 1 LASTPIN (-6425 1000) $PN 1
J 0
(-6413 1012);
DISPLAY 0.489362 (-6413 1012);
PAINT MONO (-6413 1012);
FORCEPROP 1 LASTPIN (-6225 1000) $PN 2
J 0
(-6263 1012);
DISPLAY 0.489362 (-6263 1012);
PAINT MONO (-6263 1012);
FORCEPROP 1 LAST PART_NUMBER CS00002JB38
J 0
(-6575 950);
DISPLAY 0.489362 (-6575 950);
PAINT SKYBLUE (-6575 950);
FORCEPROP 1 LAST PACK_TYPE 0402LF
J 0
(-6225 925);
DISPLAY 0.489362 (-6225 925);
PAINT SKYBLUE (-6225 925);
FORCEPROP 1 LAST WATTAGE 1/16W
J 0
(-6225 950);
DISPLAY 0.489362 (-6225 950);
PAINT SKYBLUE (-6225 950);
FORCEPROP 1 LAST MATERIAL CHIP
J 0
(-6575 925);
DISPLAY 0.489362 (-6575 925);
PAINT SKYBLUE (-6575 925);
FORCEPROP 1 LAST TOLERANCE 5%
J 0
(-6200 1025);
DISPLAY 0.489362 (-6200 1025);
PAINT SKYBLUE (-6200 1025);
FORCEPROP 1 LAST VALUE 0
J 2
(-6450 1025);
DISPLAY 0.489362 (-6450 1025);
PAINT SKYBLUE (-6450 1025);
FORCEPROP 2 LAST CDS_LIB pure_quanta
J 0
(-6325 1000);
DISPLAY INVISIBLE (-6325 1000);
FORCEPROP 1 LAST PATH I113
J 0
(-6375 1150);
DISPLAY 0.978723 (-6375 1150);
PAINT WHITE (-6375 1150);
DISPLAY INVISIBLE (-6375 1150);
FORCEADD Q_CAP..2
(-5650 1250);
FORCEPROP 1 LAST LOCATION PC465
J 1
(-5650 1325);
DISPLAY 0.489362 (-5650 1325);
PAINT SKYBLUE (-5650 1325);
FORCEPROP 0 LAST $SEC 1
J 0
(-5650 1400);
DISPLAY 0.680851 (-5650 1400);
PAINT MONO (-5650 1400);
DISPLAY INVISIBLE (-5650 1400);
FORCEPROP 0 LAST CDS_SEC 1
J 0
(-5650 1400);
DISPLAY 1.021277 (-5650 1400);
DISPLAY INVISIBLE (-5650 1400);
FORCEPROP 1 LASTPIN (-5750 1250) $PN 1
J 0
(-5760 1265);
DISPLAY 0.489362 (-5760 1265);
PAINT MONO (-5760 1265);
FORCEPROP 1 LASTPIN (-5550 1250) $PN 2
J 0
(-5565 1265);
DISPLAY 0.489362 (-5565 1265);
PAINT MONO (-5565 1265);
FORCEPROP 1 LAST TOLERANCE 5%
J 0
(-5525 1125);
DISPLAY 0.489362 (-5525 1125);
PAINT SKYBLUE (-5525 1125);
FORCEPROP 1 LAST MATERIAL EMPTY
J 0
(-5925 1125);
DISPLAY 0.489362 (-5925 1125);
PAINT RED (-5925 1125);
FORCEPROP 1 LAST VALUE 1000PF
J 2
(-5775 1300);
DISPLAY 0.489362 (-5775 1300);
PAINT SKYBLUE (-5775 1300);
FORCEPROP 1 LAST PART_NUMBER TMP_QCH21006JB10
J 1
(-5800 1175);
DISPLAY 0.489362 (-5800 1175);
PAINT SKYBLUE (-5800 1175);
FORCEPROP 1 LAST VOLTAGE 50V
J 0
(-5525 1300);
DISPLAY 0.489362 (-5525 1300);
PAINT SKYBLUE (-5525 1300);
FORCEPROP 1 LAST PACK_TYPE 0402
J 0
(-5525 1175);
DISPLAY 0.489362 (-5525 1175);
PAINT SKYBLUE (-5525 1175);
FORCEPROP 2 LAST CDS_LIB pure_quanta
J 0
(-5650 1250);
DISPLAY INVISIBLE (-5650 1250);
FORCEPROP 1 LAST PATH I114
J 0
(-5650 1450);
DISPLAY 0.978723 (-5650 1450);
PAINT WHITE (-5650 1450);
DISPLAY INVISIBLE (-5650 1450);
FORCEADD UNIVERSAL_GND..1
(-5325 1125);
FORCEPROP 3 LASTPIN (-5325 1175) SIG_NAME GND\g
J 0
(-5315 1185);
DISPLAY 0.659574 (-5315 1185);
PAINT MONO (-5315 1185);
DISPLAY INVISIBLE (-5315 1185);
FORCEPROP 2 LAST CDS_LIB pure_quanta_power
J 0
(-5325 1125);
DISPLAY INVISIBLE (-5325 1125);
FORCEPROP 1 LAST PATH I116
J 0
(-5250 1125);
DISPLAY 0.872340 (-5250 1125);
PAINT AQUA (-5250 1125);
DISPLAY INVISIBLE (-5250 1125);
FORCEPROP 1 LAST HDL_POWER GND
J 1
(-5300 1050);
DISPLAY 0.872340 (-5300 1050);
PAINT GREEN (-5300 1050);
DISPLAY INVISIBLE (-5300 1050);
FORCEADD Q_CAP..1
(-6475 625);
FORCEPROP 1 LAST LOCATION PC462
J 0
(-6425 725);
DISPLAY 0.489362 (-6425 725);
PAINT SKYBLUE (-6425 725);
FORCEPROP 0 LAST $SEC 1
J 0
(-6425 750);
DISPLAY 0.680851 (-6425 750);
PAINT MONO (-6425 750);
DISPLAY INVISIBLE (-6425 750);
FORCEPROP 0 LAST CDS_SEC 1
J 0
(-6425 750);
DISPLAY 1.021277 (-6425 750);
DISPLAY INVISIBLE (-6425 750);
FORCEPROP 1 LASTPIN (-6475 725) $PN 1
J 0
(-6465 705);
DISPLAY 0.489362 (-6465 705);
PAINT MONO (-6465 705);
FORCEPROP 1 LASTPIN (-6475 525) $PN 2
J 0
(-6465 505);
DISPLAY 0.489362 (-6465 505);
PAINT MONO (-6465 505);
FORCEPROP 1 LAST MATERIAL X7R
J 0
(-6425 525);
DISPLAY 0.489362 (-6425 525);
PAINT SKYBLUE (-6425 525);
FORCEPROP 1 LAST TOLERANCE 10%
J 0
(-6425 575);
DISPLAY 0.489362 (-6425 575);
PAINT SKYBLUE (-6425 575);
FORCEPROP 1 LAST VALUE 0.1UF
J 0
(-6425 675);
DISPLAY 0.489362 (-6425 675);
PAINT SKYBLUE (-6425 675);
FORCEPROP 1 LAST PART_NUMBER CH4104K1B00
J 0
(-6425 475);
DISPLAY 0.489362 (-6425 475);
PAINT SKYBLUE (-6425 475);
FORCEPROP 1 LAST VOLTAGE 25V
J 0
(-6425 625);
DISPLAY 0.489362 (-6425 625);
PAINT SKYBLUE (-6425 625);
FORCEPROP 1 LAST PACK_TYPE 0402
J 0
(-6425 425);
DISPLAY 0.489362 (-6425 425);
PAINT SKYBLUE (-6425 425);
FORCEPROP 2 LAST CDS_LIB pure_quanta
J 0
(-6475 625);
DISPLAY INVISIBLE (-6475 625);
FORCEPROP 1 LAST PATH I118
J 0
(-6425 775);
DISPLAY 0.978723 (-6425 775);
PAINT WHITE (-6425 775);
DISPLAY INVISIBLE (-6425 775);
FORCEADD OFFPAGE..4
R 2
(-9125 1425);
FORCEPROP 2 LAST $XR0 81 
J 0
(-9346 1425);
DISPLAY 0.638298 (-9346 1425);
PAINT MONO (-9346 1425);
FORCEPROP 2 LAST CDS_LIB standard
J 0
(-9125 1425);
DISPLAY INVISIBLE (-9125 1425);
FORCEPROP 1 LAST OFFPAGE TRUE
J 2
(-9450 1300);
DISPLAY 0.872340 (-9450 1300);
PAINT GREEN (-9450 1300);
DISPLAY INVISIBLE (-9450 1300);
FORCEPROP 1 LAST COMMENT_BODY TRUE
J 2
(-9100 1325);
DISPLAY 0.872340 (-9100 1325);
PAINT GREEN (-9100 1325);
DISPLAY INVISIBLE (-9100 1325);
FORCEPROP 2 LAST PATH I119
J 0
(-9075 1500);
DISPLAY 1.021277 (-9075 1500);
DISPLAY INVISIBLE (-9075 1500);
FORCEADD UNIVERSAL_GND..1
(-2925 5425);
FORCEPROP 3 LASTPIN (-2925 5475) SIG_NAME GND\g
J 0
(-2915 5485);
DISPLAY 0.659574 (-2915 5485);
PAINT MONO (-2915 5485);
DISPLAY INVISIBLE (-2915 5485);
FORCEPROP 2 LAST CDS_LIB pure_quanta_power
J 0
(-2925 5425);
DISPLAY INVISIBLE (-2925 5425);
FORCEPROP 1 LAST PATH I12
J 0
(-2850 5425);
DISPLAY 0.872340 (-2850 5425);
PAINT AQUA (-2850 5425);
DISPLAY INVISIBLE (-2850 5425);
FORCEPROP 1 LAST HDL_POWER GND
J 1
(-2900 5350);
DISPLAY 0.872340 (-2900 5350);
PAINT GREEN (-2900 5350);
DISPLAY INVISIBLE (-2900 5350);
FORCEADD CONN3_HBB1031L300D8H..1
R 6
(-6475 4400);
FORCEPROP 1 LAST LOCATION PJ1
J 0
(-6575 4150);
DISPLAY 0.468085 (-6575 4150);
PAINT SKYBLUE (-6575 4150);
FORCEPROP 0 LAST $SEC 1
J 0
(-6575 4225);
DISPLAY 0.680851 (-6575 4225);
PAINT MONO (-6575 4225);
DISPLAY INVISIBLE (-6575 4225);
FORCEPROP 0 LAST CDS_SEC 1
J 2
(-6425 3952);
DISPLAY 1.021277 (-6425 3952);
DISPLAY INVISIBLE (-6425 3952);
FORCEPROP 0 LASTPIN (-6250 4275) $PN 1
J 0
(-6240 4285);
DISPLAY 0.680851 (-6240 4285);
PAINT MONO (-6240 4285);
FORCEPROP 0 LASTPIN (-6250 4375) $PN 2
J 0
(-6240 4385);
DISPLAY 0.680851 (-6240 4385);
PAINT MONO (-6240 4385);
FORCEPROP 0 LASTPIN (-6250 4475) $PN 3
J 0
(-6240 4485);
DISPLAY 0.680851 (-6240 4485);
PAINT MONO (-6240 4485);
FORCEPROP 1 LAST PART_NUMBER DFHD03MS162
J 0
(-6575 4100);
DISPLAY 0.468085 (-6575 4100);
PAINT SKYBLUE (-6575 4100);
FORCEPROP 1 LAST MATERIAL IO
J 0
(-6575 4200);
DISPLAY 0.468085 (-6575 4200);
PAINT SKYBLUE (-6575 4200);
FORCEPROP 0 LAST VALUE CONN3_HBB1031-L300D-8H
J 2
(-6125 4150);
DISPLAY 0.489362 (-6125 4150);
PAINT SKYBLUE (-6125 4150);
DISPLAY INVISIBLE (-6125 4150);
FORCEPROP 0 LAST PART_TYPE THLF
J 2
(-6400 4127);
DISPLAY 1.021277 (-6400 4127);
DISPLAY INVISIBLE (-6400 4127);
FORCEPROP 2 LAST CDS_LIB pure_quanta
J 0
(-6475 4353);
DISPLAY INVISIBLE (-6475 4353);
FORCEPROP 1 LAST CDS_LMAN_SYM_OUTLINE -75,175,75,-175
J 0
(-6475 4378);
DISPLAY 0.468085 (-6475 4378);
PAINT GREEN (-6475 4378);
DISPLAY INVISIBLE (-6475 4378);
FORCEPROP 1 LAST PATH I123
J 0
(-6475 4366);
DISPLAY 0.723404 (-6475 4366);
PAINT GREEN (-6475 4366);
DISPLAY INVISIBLE (-6475 4366);
FORCEPROP 1 LAST NEEDS_NO_SIZE TRUE
J 0
(-6475 4366);
DISPLAY 0.723404 (-6475 4366);
PAINT GREEN (-6475 4366);
DISPLAY INVISIBLE (-6475 4366);
FORCEADD UNIVERSAL_GND..1
(-6175 4150);
FORCEPROP 3 LASTPIN (-6175 4200) SIG_NAME GND\g
J 0
(-6165 4210);
DISPLAY 0.659574 (-6165 4210);
PAINT MONO (-6165 4210);
DISPLAY INVISIBLE (-6165 4210);
FORCEPROP 1 LAST HDL_POWER GND
J 1
(-6150 4075);
DISPLAY 0.872340 (-6150 4075);
PAINT GREEN (-6150 4075);
DISPLAY INVISIBLE (-6150 4075);
FORCEPROP 1 LAST PATH I124
J 0
(-6100 4150);
DISPLAY 0.872340 (-6100 4150);
PAINT AQUA (-6100 4150);
DISPLAY INVISIBLE (-6100 4150);
FORCEPROP 2 LAST CDS_LIB pure_quanta_power
J 0
(-6175 4150);
DISPLAY INVISIBLE (-6175 4150);
FORCEADD Q_CAP..1
(-2925 5650);
FORCEPROP 1 LAST LOCATION PC470
J 0
(-2875 5750);
DISPLAY 0.489362 (-2875 5750);
PAINT SKYBLUE (-2875 5750);
FORCEPROP 0 LAST $SEC 1
J 0
(-2875 5775);
DISPLAY 0.680851 (-2875 5775);
PAINT MONO (-2875 5775);
DISPLAY INVISIBLE (-2875 5775);
FORCEPROP 0 LAST CDS_SEC 1
J 0
(-2875 5775);
DISPLAY 1.021277 (-2875 5775);
DISPLAY INVISIBLE (-2875 5775);
FORCEPROP 1 LASTPIN (-2925 5750) $PN 1
J 0
(-2915 5730);
DISPLAY 0.489362 (-2915 5730);
PAINT MONO (-2915 5730);
FORCEPROP 1 LASTPIN (-2925 5550) $PN 2
J 0
(-2915 5530);
DISPLAY 0.489362 (-2915 5530);
PAINT MONO (-2915 5530);
FORCEPROP 1 LAST MATERIAL X6S
J 0
(-2875 5550);
DISPLAY 0.489362 (-2875 5550);
PAINT SKYBLUE (-2875 5550);
FORCEPROP 1 LAST TOLERANCE 20%
J 0
(-2875 5600);
DISPLAY 0.489362 (-2875 5600);
PAINT SKYBLUE (-2875 5600);
FORCEPROP 1 LAST VALUE 10UF
J 0
(-2875 5700);
DISPLAY 0.489362 (-2875 5700);
PAINT SKYBLUE (-2875 5700);
FORCEPROP 1 LAST PART_NUMBER CH6101MEB01
J 0
(-2875 5500);
DISPLAY 0.489362 (-2875 5500);
PAINT SKYBLUE (-2875 5500);
FORCEPROP 1 LAST VOLTAGE 6.3V
J 0
(-2875 5650);
DISPLAY 0.489362 (-2875 5650);
PAINT SKYBLUE (-2875 5650);
FORCEPROP 1 LAST PACK_TYPE C0402
J 0
(-2875 5450);
DISPLAY 0.489362 (-2875 5450);
PAINT SKYBLUE (-2875 5450);
FORCEPROP 2 LAST CDS_LIB pure_quanta
J 0
(-2925 5650);
DISPLAY INVISIBLE (-2925 5650);
FORCEPROP 1 LAST PATH I13
J 0
(-2875 5800);
DISPLAY 0.978723 (-2875 5800);
PAINT WHITE (-2875 5800);
DISPLAY INVISIBLE (-2875 5800);
FORCEADD Q_RES..1
(-8575 1425);
FORCEPROP 1 LAST LOCATION PR282
J 0
(-8625 1475);
DISPLAY 0.489362 (-8625 1475);
PAINT SKYBLUE (-8625 1475);
FORCEPROP 0 LAST $SEC 1
J 0
(-8625 1500);
DISPLAY 0.680851 (-8625 1500);
PAINT MONO (-8625 1500);
DISPLAY INVISIBLE (-8625 1500);
FORCEPROP 0 LAST CDS_SEC 1
J 0
(-8625 1500);
DISPLAY 1.021277 (-8625 1500);
DISPLAY INVISIBLE (-8625 1500);
FORCEPROP 1 LASTPIN (-8675 1425) $PN 1
J 0
(-8663 1437);
DISPLAY 0.489362 (-8663 1437);
PAINT MONO (-8663 1437);
FORCEPROP 1 LASTPIN (-8475 1425) $PN 2
J 0
(-8513 1437);
DISPLAY 0.489362 (-8513 1437);
PAINT MONO (-8513 1437);
FORCEPROP 1 LAST WATTAGE 1/16W
J 0
(-8475 1375);
DISPLAY 0.489362 (-8475 1375);
PAINT SKYBLUE (-8475 1375);
FORCEPROP 1 LAST TOLERANCE 5%
J 0
(-8450 1475);
DISPLAY 0.489362 (-8450 1475);
PAINT SKYBLUE (-8450 1475);
FORCEPROP 1 LAST VALUE 0
J 2
(-8700 1475);
DISPLAY 0.489362 (-8700 1475);
PAINT SKYBLUE (-8700 1475);
FORCEPROP 1 LAST PART_NUMBER CS00002JB38
J 0
(-8825 1375);
DISPLAY 0.489362 (-8825 1375);
PAINT SKYBLUE (-8825 1375);
FORCEPROP 1 LAST PACK_TYPE 0402LF
J 0
(-8475 1350);
DISPLAY 0.489362 (-8475 1350);
PAINT SKYBLUE (-8475 1350);
FORCEPROP 1 LAST MATERIAL CHIP
J 0
(-8825 1350);
DISPLAY 0.489362 (-8825 1350);
PAINT SKYBLUE (-8825 1350);
FORCEPROP 2 LAST CDS_LIB pure_quanta
J 0
(-8575 1425);
DISPLAY INVISIBLE (-8575 1425);
FORCEPROP 1 LAST PATH I139
J 0
(-8625 1575);
DISPLAY 0.978723 (-8625 1575);
PAINT WHITE (-8625 1575);
DISPLAY INVISIBLE (-8625 1575);
FORCEADD VCC_CORE..1
(-2050 6375);
FORCEPROP 3 LASTPIN (-2050 6325) SIG_NAME P3V3_STBY\g
J 0
(-2040 6335);
DISPLAY 0.659574 (-2040 6335);
PAINT MONO (-2040 6335);
DISPLAY INVISIBLE (-2040 6335);
FORCEPROP 1 LAST HDL_POWER P3V3_STBY
J 1
(-2050 6425);
DISPLAY 0.489362 (-2050 6425);
PAINT GREEN (-2050 6425);
FORCEPROP 2 LAST CDS_LIB pure_quanta_power
J 0
(-2050 6375);
DISPLAY INVISIBLE (-2050 6375);
FORCEPROP 1 LAST PATH I14
J 0
(-2000 6400);
DISPLAY 0.872340 (-2000 6400);
PAINT AQUA (-2000 6400);
DISPLAY INVISIBLE (-2000 6400);
FORCEADD Q_CAP..1
(-8175 1200);
FORCEPROP 1 LAST LOCATION PC461
J 0
(-8125 1300);
DISPLAY 0.489362 (-8125 1300);
PAINT SKYBLUE (-8125 1300);
FORCEPROP 0 LAST $SEC 1
J 0
(-8125 1325);
DISPLAY 0.680851 (-8125 1325);
PAINT MONO (-8125 1325);
DISPLAY INVISIBLE (-8125 1325);
FORCEPROP 0 LAST CDS_SEC 1
J 0
(-8125 1325);
DISPLAY 1.021277 (-8125 1325);
DISPLAY INVISIBLE (-8125 1325);
FORCEPROP 1 LASTPIN (-8175 1300) $PN 1
J 0
(-8165 1280);
DISPLAY 0.489362 (-8165 1280);
PAINT MONO (-8165 1280);
FORCEPROP 1 LASTPIN (-8175 1100) $PN 2
J 0
(-8165 1080);
DISPLAY 0.489362 (-8165 1080);
PAINT MONO (-8165 1080);
FORCEPROP 1 LAST VALUE 1000PF
J 0
(-8125 1250);
DISPLAY 0.489362 (-8125 1250);
PAINT SKYBLUE (-8125 1250);
FORCEPROP 1 LAST MATERIAL X7R
J 0
(-8125 1100);
DISPLAY 0.489362 (-8125 1100);
PAINT SKYBLUE (-8125 1100);
FORCEPROP 1 LAST VOLTAGE 50V
J 0
(-8125 1200);
DISPLAY 0.489362 (-8125 1200);
PAINT SKYBLUE (-8125 1200);
FORCEPROP 1 LAST PACK_TYPE 0402
J 0
(-8125 1000);
DISPLAY 0.489362 (-8125 1000);
PAINT SKYBLUE (-8125 1000);
FORCEPROP 1 LAST PART_NUMBER TMP_QCH21006JB10
J 0
(-8125 1050);
DISPLAY 0.489362 (-8125 1050);
PAINT SKYBLUE (-8125 1050);
FORCEPROP 1 LAST TOLERANCE 5%
J 0
(-8125 1150);
DISPLAY 0.489362 (-8125 1150);
PAINT SKYBLUE (-8125 1150);
FORCEPROP 2 LAST CDS_LIB pure_quanta
J 0
(-8175 1200);
DISPLAY INVISIBLE (-8175 1200);
FORCEPROP 1 LAST PATH I140
J 0
(-8125 1350);
DISPLAY 0.978723 (-8125 1350);
PAINT WHITE (-8125 1350);
DISPLAY INVISIBLE (-8125 1350);
FORCEADD UNIVERSAL_GND..1
(-8175 1000);
FORCEPROP 3 LASTPIN (-8175 1050) SIG_NAME GND\g
J 0
(-8165 1060);
DISPLAY 0.659574 (-8165 1060);
PAINT MONO (-8165 1060);
DISPLAY INVISIBLE (-8165 1060);
FORCEPROP 2 LAST CDS_LIB pure_quanta_power
J 0
(-8175 1000);
DISPLAY INVISIBLE (-8175 1000);
FORCEPROP 1 LAST PATH I141
J 0
(-8100 1000);
DISPLAY 0.872340 (-8100 1000);
PAINT AQUA (-8100 1000);
DISPLAY INVISIBLE (-8100 1000);
FORCEPROP 1 LAST HDL_POWER GND
J 1
(-8150 925);
DISPLAY 0.872340 (-8150 925);
PAINT GREEN (-8150 925);
DISPLAY INVISIBLE (-8150 925);
FORCEADD UNIVERSAL_GND..1
(-7825 4775);
FORCEPROP 3 LASTPIN (-7825 4825) SIG_NAME GND\g
J 0
(-7815 4835);
DISPLAY 0.659574 (-7815 4835);
PAINT MONO (-7815 4835);
DISPLAY INVISIBLE (-7815 4835);
FORCEPROP 2 LAST CDS_LIB pure_quanta_power
J 0
(-7825 4775);
DISPLAY INVISIBLE (-7825 4775);
FORCEPROP 1 LAST PATH I144
J 0
(-7750 4775);
DISPLAY 0.872340 (-7750 4775);
PAINT AQUA (-7750 4775);
DISPLAY INVISIBLE (-7750 4775);
FORCEPROP 1 LAST HDL_POWER GND
J 1
(-7800 4700);
DISPLAY 0.872340 (-7800 4700);
PAINT GREEN (-7800 4700);
DISPLAY INVISIBLE (-7800 4700);
FORCEADD UNIVERSAL_GND..1
(-7600 4775);
FORCEPROP 3 LASTPIN (-7600 4825) SIG_NAME GND\g
J 0
(-7590 4835);
DISPLAY 0.659574 (-7590 4835);
PAINT MONO (-7590 4835);
DISPLAY INVISIBLE (-7590 4835);
FORCEPROP 2 LAST CDS_LIB pure_quanta_power
J 0
(-7600 4775);
DISPLAY INVISIBLE (-7600 4775);
FORCEPROP 1 LAST PATH I145
J 0
(-7525 4775);
DISPLAY 0.872340 (-7525 4775);
PAINT AQUA (-7525 4775);
DISPLAY INVISIBLE (-7525 4775);
FORCEPROP 1 LAST HDL_POWER GND
J 1
(-7575 4700);
DISPLAY 0.872340 (-7575 4700);
PAINT GREEN (-7575 4700);
DISPLAY INVISIBLE (-7575 4700);
FORCEADD Q_RES..1
(-6025 5350);
FORCEPROP 1 LAST LOCATION PR304
J 0
(-6075 5400);
DISPLAY 0.489362 (-6075 5400);
PAINT SKYBLUE (-6075 5400);
FORCEPROP 0 LAST $SEC 1
J 0
(-6075 5425);
DISPLAY 0.680851 (-6075 5425);
PAINT MONO (-6075 5425);
DISPLAY INVISIBLE (-6075 5425);
FORCEPROP 0 LAST CDS_SEC 1
J 0
(-6075 5425);
DISPLAY 1.021277 (-6075 5425);
DISPLAY INVISIBLE (-6075 5425);
FORCEPROP 1 LASTPIN (-6125 5350) $PN 1
J 0
(-6113 5362);
DISPLAY 0.489362 (-6113 5362);
PAINT MONO (-6113 5362);
FORCEPROP 1 LASTPIN (-5925 5350) $PN 2
J 0
(-5963 5362);
DISPLAY 0.489362 (-5963 5362);
PAINT MONO (-5963 5362);
FORCEPROP 1 LAST WATTAGE 1/16W
J 0
(-5925 5300);
DISPLAY 0.489362 (-5925 5300);
PAINT SKYBLUE (-5925 5300);
FORCEPROP 1 LAST MATERIAL CHIP
J 0
(-6275 5275);
DISPLAY 0.489362 (-6275 5275);
PAINT SKYBLUE (-6275 5275);
FORCEPROP 1 LAST TOLERANCE 5%
J 0
(-5900 5375);
DISPLAY 0.489362 (-5900 5375);
PAINT SKYBLUE (-5900 5375);
FORCEPROP 1 LAST VALUE 0
J 2
(-6150 5375);
DISPLAY 0.489362 (-6150 5375);
PAINT SKYBLUE (-6150 5375);
FORCEPROP 1 LAST PART_NUMBER CS00002JB38
J 0
(-6275 5300);
DISPLAY 0.489362 (-6275 5300);
PAINT SKYBLUE (-6275 5300);
FORCEPROP 1 LAST PACK_TYPE 0402LF
J 0
(-5925 5275);
DISPLAY 0.489362 (-5925 5275);
PAINT SKYBLUE (-5925 5275);
FORCEPROP 2 LAST CDS_LIB pure_quanta
J 0
(-6025 5350);
DISPLAY INVISIBLE (-6025 5350);
FORCEPROP 1 LAST PATH I148
J 0
(-6075 5500);
DISPLAY 0.978723 (-6075 5500);
PAINT WHITE (-6075 5500);
DISPLAY INVISIBLE (-6075 5500);
FORCEADD Q_RES..1
(-6025 5200);
FORCEPROP 1 LAST LOCATION PR305
J 0
(-6075 5250);
DISPLAY 0.489362 (-6075 5250);
PAINT SKYBLUE (-6075 5250);
FORCEPROP 0 LAST $SEC 1
J 0
(-6075 5275);
DISPLAY 0.680851 (-6075 5275);
PAINT MONO (-6075 5275);
DISPLAY INVISIBLE (-6075 5275);
FORCEPROP 0 LAST CDS_SEC 1
J 0
(-6075 5275);
DISPLAY 1.021277 (-6075 5275);
DISPLAY INVISIBLE (-6075 5275);
FORCEPROP 1 LASTPIN (-6125 5200) $PN 1
J 0
(-6113 5212);
DISPLAY 0.489362 (-6113 5212);
PAINT MONO (-6113 5212);
FORCEPROP 1 LASTPIN (-5925 5200) $PN 2
J 0
(-5963 5212);
DISPLAY 0.489362 (-5963 5212);
PAINT MONO (-5963 5212);
FORCEPROP 1 LAST PACK_TYPE 0402LF
J 0
(-5925 5125);
DISPLAY 0.489362 (-5925 5125);
PAINT SKYBLUE (-5925 5125);
FORCEPROP 1 LAST WATTAGE 1/16W
J 0
(-5925 5150);
DISPLAY 0.489362 (-5925 5150);
PAINT SKYBLUE (-5925 5150);
FORCEPROP 1 LAST MATERIAL CHIP
J 0
(-6275 5125);
DISPLAY 0.489362 (-6275 5125);
PAINT SKYBLUE (-6275 5125);
FORCEPROP 1 LAST TOLERANCE 5%
J 0
(-5900 5225);
DISPLAY 0.489362 (-5900 5225);
PAINT SKYBLUE (-5900 5225);
FORCEPROP 1 LAST VALUE 0
J 2
(-6150 5225);
DISPLAY 0.489362 (-6150 5225);
PAINT SKYBLUE (-6150 5225);
FORCEPROP 1 LAST PART_NUMBER CS00002JB38
J 0
(-6275 5150);
DISPLAY 0.489362 (-6275 5150);
PAINT SKYBLUE (-6275 5150);
FORCEPROP 2 LAST CDS_LIB pure_quanta
J 0
(-6025 5200);
DISPLAY INVISIBLE (-6025 5200);
FORCEPROP 1 LAST PATH I149
J 0
(-6075 5350);
DISPLAY 0.978723 (-6075 5350);
PAINT WHITE (-6075 5350);
DISPLAY INVISIBLE (-6075 5350);
FORCEADD OFFPAGE..5
R 2
(-2475 5800);
FORCEPROP 2 LAST $XR4 175 
J 0
(-1806 5800);
DISPLAY 0.638298 (-1806 5800);
PAINT MONO (-1806 5800);
FORCEPROP 2 LAST $XR3 174 
J 0
(-1926 5800);
DISPLAY 0.638298 (-1926 5800);
PAINT MONO (-1926 5800);
FORCEPROP 2 LAST $XR2 172 
J 0
(-2046 5800);
DISPLAY 0.638298 (-2046 5800);
PAINT MONO (-2046 5800);
FORCEPROP 2 LAST $XR1 171 
J 0
(-2166 5800);
DISPLAY 0.638298 (-2166 5800);
PAINT MONO (-2166 5800);
FORCEPROP 2 LAST $XR0 170 
J 0
(-2286 5800);
DISPLAY 0.638298 (-2286 5800);
PAINT MONO (-2286 5800);
FORCEPROP 2 LAST CDS_LIB standard
J 2
(-2475 5800);
DISPLAY INVISIBLE (-2475 5800);
FORCEPROP 1 LAST OFFPAGE TRUE
J 2
(-2800 5675);
DISPLAY 0.872340 (-2800 5675);
PAINT GREEN (-2800 5675);
DISPLAY INVISIBLE (-2800 5675);
FORCEPROP 1 LAST COMMENT_BODY TRUE
J 2
(-2575 5725);
DISPLAY 0.872340 (-2575 5725);
PAINT GREEN (-2575 5725);
DISPLAY INVISIBLE (-2575 5725);
FORCEPROP 2 LAST PATH I15
J 2
(-2525 5875);
DISPLAY 1.021277 (-2525 5875);
DISPLAY INVISIBLE (-2525 5875);
FORCEADD OFFPAGE..4
R 2
(-6625 5950);
FORCEPROP 2 LAST $XR0 79 
J 0
(-6846 5950);
DISPLAY 0.638298 (-6846 5950);
PAINT MONO (-6846 5950);
FORCEPROP 2 LAST CDS_LIB standard
J 0
(-6625 5950);
DISPLAY INVISIBLE (-6625 5950);
FORCEPROP 1 LAST OFFPAGE TRUE
J 2
(-6950 5825);
DISPLAY 0.872340 (-6950 5825);
PAINT GREEN (-6950 5825);
DISPLAY INVISIBLE (-6950 5825);
FORCEPROP 1 LAST COMMENT_BODY TRUE
J 2
(-6600 5850);
DISPLAY 0.872340 (-6600 5850);
PAINT GREEN (-6600 5850);
DISPLAY INVISIBLE (-6600 5850);
FORCEPROP 2 LAST PATH I150
J 0
(-6575 6025);
DISPLAY 1.021277 (-6575 6025);
DISPLAY INVISIBLE (-6575 6025);
FORCEADD Q_RES..1
(-2475 6275);
FORCEPROP 1 LAST LOCATION PR316
J 0
(-2525 6325);
DISPLAY 0.489362 (-2525 6325);
PAINT SKYBLUE (-2525 6325);
FORCEPROP 0 LAST $SEC 1
J 0
(-2525 6375);
DISPLAY 0.680851 (-2525 6375);
PAINT MONO (-2525 6375);
DISPLAY INVISIBLE (-2525 6375);
FORCEPROP 0 LAST CDS_SEC 1
J 0
(-2525 6375);
DISPLAY 1.021277 (-2525 6375);
DISPLAY INVISIBLE (-2525 6375);
FORCEPROP 1 LASTPIN (-2575 6275) $PN 1
J 0
(-2563 6287);
DISPLAY 0.489362 (-2563 6287);
PAINT MONO (-2563 6287);
FORCEPROP 1 LASTPIN (-2375 6275) $PN 2
J 0
(-2413 6287);
DISPLAY 0.489362 (-2413 6287);
PAINT MONO (-2413 6287);
FORCEPROP 1 LAST WATTAGE 1/16W
J 0
(-2350 6200);
DISPLAY 0.489362 (-2350 6200);
PAINT SKYBLUE (-2350 6200);
FORCEPROP 1 LAST MATERIAL CHIP
J 0
(-2350 6225);
DISPLAY 0.489362 (-2350 6225);
PAINT SKYBLUE (-2350 6225);
FORCEPROP 1 LAST TOLERANCE 1%
J 0
(-2350 6300);
DISPLAY 0.489362 (-2350 6300);
PAINT SKYBLUE (-2350 6300);
FORCEPROP 1 LAST VALUE 1
J 2
(-2625 6300);
DISPLAY 0.489362 (-2625 6300);
PAINT SKYBLUE (-2625 6300);
FORCEPROP 1 LAST PART_NUMBER CS-1002FB23
J 0
(-2650 6225);
DISPLAY 0.489362 (-2650 6225);
PAINT SKYBLUE (-2650 6225);
FORCEPROP 1 LAST PACK_TYPE 0402LF
J 0
(-2650 6200);
DISPLAY 0.489362 (-2650 6200);
PAINT SKYBLUE (-2650 6200);
FORCEPROP 2 LAST CDS_LIB pure_quanta
J 0
(-2475 6275);
DISPLAY INVISIBLE (-2475 6275);
FORCEPROP 1 LAST PATH I151
J 0
(-2525 6425);
DISPLAY 0.978723 (-2525 6425);
PAINT WHITE (-2525 6425);
DISPLAY INVISIBLE (-2525 6425);
FORCEADD OFFPAGE..4
(-2475 1200);
FORCEPROP 2 LAST $XR1 175 
J 0
(-2169 1200);
DISPLAY 0.638298 (-2169 1200);
PAINT MONO (-2169 1200);
FORCEPROP 2 LAST $XR0 174 
J 0
(-2289 1200);
DISPLAY 0.638298 (-2289 1200);
PAINT MONO (-2289 1200);
FORCEPROP 2 LAST CDS_LIB standard
J 0
(-2475 1200);
DISPLAY INVISIBLE (-2475 1200);
FORCEPROP 1 LAST OFFPAGE TRUE
J 0
(-2150 1075);
DISPLAY 0.872340 (-2150 1075);
PAINT GREEN (-2150 1075);
DISPLAY INVISIBLE (-2150 1075);
FORCEPROP 1 LAST COMMENT_BODY TRUE
J 0
(-2500 1100);
DISPLAY 0.872340 (-2500 1100);
PAINT GREEN (-2500 1100);
DISPLAY INVISIBLE (-2500 1100);
FORCEPROP 2 LAST PATH I152
J 0
(-2300 1275);
DISPLAY 1.021277 (-2300 1275);
DISPLAY INVISIBLE (-2300 1275);
FORCEADD OFFPAGE..4
(-3050 900);
FORCEPROP 2 LAST $XR2 172 
J 0
(-2864 936);
DISPLAY 0.638298 (-2864 936);
PAINT MONO (-2864 936);
FORCEPROP 2 LAST $XR1 171 
J 0
(-2864 864);
DISPLAY 0.638298 (-2864 864);
PAINT MONO (-2864 864);
FORCEPROP 2 LAST $XR0 170 
J 0
(-2864 900);
DISPLAY 0.638298 (-2864 900);
PAINT MONO (-2864 900);
FORCEPROP 2 LAST CDS_LIB standard
J 0
(-3050 900);
DISPLAY INVISIBLE (-3050 900);
FORCEPROP 1 LAST OFFPAGE TRUE
J 0
(-2725 775);
DISPLAY 0.872340 (-2725 775);
PAINT GREEN (-2725 775);
DISPLAY INVISIBLE (-2725 775);
FORCEPROP 1 LAST COMMENT_BODY TRUE
J 0
(-3075 800);
DISPLAY 0.872340 (-3075 800);
PAINT GREEN (-3075 800);
DISPLAY INVISIBLE (-3075 800);
FORCEPROP 2 LAST PATH I153
J 0
(-2875 975);
DISPLAY 1.021277 (-2875 975);
DISPLAY INVISIBLE (-2875 975);
FORCEADD MOSFET_PCH_GDS_ESD_PROTECTED..1
R 6
(-7125 1850);
FORCEPROP 1 LAST LOCATION PQ13
J 0
(-6950 1700);
DISPLAY 0.489362 (-6950 1700);
PAINT SKYBLUE (-6950 1700);
FORCEPROP 0 LAST $SEC 1
J 0
(-6950 1875);
DISPLAY 0.680851 (-6950 1875);
PAINT MONO (-6950 1875);
DISPLAY INVISIBLE (-6950 1875);
FORCEPROP 0 LAST CDS_SEC 1
J 0
(-6950 1875);
DISPLAY 1.021277 (-6950 1875);
DISPLAY INVISIBLE (-6950 1875);
FORCEPROP 0 LASTPIN (-7100 1550) $PN D
R 1
J 2
(-7110 1540);
DISPLAY 0.489362 (-7110 1540);
PAINT MONO (-7110 1540);
FORCEPROP 0 LASTPIN (-7400 1850) $PN G
J 2
(-7410 1860);
DISPLAY 0.489362 (-7410 1860);
PAINT MONO (-7410 1860);
FORCEPROP 0 LASTPIN (-7100 2150) $PN S
R 1
J 0
(-7110 2160);
DISPLAY 0.489362 (-7110 2160);
PAINT MONO (-7110 2160);
FORCEPROP 1 LAST MATERIAL IC
J 0
(-6950 1852);
DISPLAY 0.489362 (-6950 1852);
PAINT SKYBLUE (-6950 1852);
FORCEPROP 2 LAST VALUE PJA3415AE
J 0
(-6950 1802);
DISPLAY 0.489362 (-6950 1802);
PAINT SKYBLUE (-6950 1802);
FORCEPROP 1 LAST PART_NUMBER BAM34150008
J 0
(-6950 1752);
DISPLAY 0.489362 (-6950 1752);
PAINT SKYBLUE (-6950 1752);
FORCEPROP 1 LAST NEEDS_NO_SIZE TRUE
J 0
(-7125 1816);
DISPLAY 0.723404 (-7125 1816);
PAINT GREEN (-7125 1816);
DISPLAY INVISIBLE (-7125 1816);
FORCEPROP 1 LAST CDS_LMAN_SYM_OUTLINE -125,150,125,-150
J 0
(-7125 1850);
DISPLAY 0.468085 (-7125 1850);
PAINT GREEN (-7125 1850);
DISPLAY INVISIBLE (-7125 1850);
FORCEPROP 2 LAST CDS_LIB pure_quanta
J 0
(-7125 1850);
DISPLAY INVISIBLE (-7125 1850);
FORCEPROP 2 LAST PART_TYPE SMLF
J 0
(-6975 1677);
DISPLAY 1.021277 (-6975 1677);
DISPLAY INVISIBLE (-6975 1677);
FORCEPROP 1 LAST PATH I154
J 0
(-7125 1850);
DISPLAY 0.723404 (-7125 1850);
PAINT GREEN (-7125 1850);
DISPLAY INVISIBLE (-7125 1850);
FORCEADD UNIVERSAL_GND..1
(-3200 5875);
FORCEPROP 3 LASTPIN (-3200 5925) SIG_NAME GND\g
J 0
(-3190 5935);
DISPLAY 0.659574 (-3190 5935);
PAINT MONO (-3190 5935);
DISPLAY INVISIBLE (-3190 5935);
FORCEPROP 2 LAST CDS_LIB pure_quanta_power
J 0
(-3200 5875);
DISPLAY INVISIBLE (-3200 5875);
FORCEPROP 1 LAST PATH I155
J 0
(-3125 5875);
DISPLAY 0.872340 (-3125 5875);
PAINT AQUA (-3125 5875);
DISPLAY INVISIBLE (-3125 5875);
FORCEPROP 1 LAST HDL_POWER GND
J 1
(-3175 5800);
DISPLAY 0.872340 (-3175 5800);
PAINT GREEN (-3175 5800);
DISPLAY INVISIBLE (-3175 5800);
FORCEADD Q_CAP..1
(-3200 6125);
FORCEPROP 1 LAST LOCATION PC12
J 0
(-3150 6225);
DISPLAY 0.489362 (-3150 6225);
PAINT SKYBLUE (-3150 6225);
FORCEPROP 0 LAST $SEC 1
J 0
(-3150 6250);
DISPLAY 0.680851 (-3150 6250);
PAINT MONO (-3150 6250);
DISPLAY INVISIBLE (-3150 6250);
FORCEPROP 0 LAST CDS_SEC 1
J 0
(-3150 6250);
DISPLAY 1.021277 (-3150 6250);
DISPLAY INVISIBLE (-3150 6250);
FORCEPROP 1 LASTPIN (-3200 6225) $PN 1
J 0
(-3190 6205);
DISPLAY 0.489362 (-3190 6205);
PAINT MONO (-3190 6205);
FORCEPROP 1 LASTPIN (-3200 6025) $PN 2
J 0
(-3190 6005);
DISPLAY 0.489362 (-3190 6005);
PAINT MONO (-3190 6005);
FORCEPROP 1 LAST MATERIAL X7R
J 0
(-3150 6025);
DISPLAY 0.489362 (-3150 6025);
PAINT SKYBLUE (-3150 6025);
FORCEPROP 1 LAST TOLERANCE 10%
J 0
(-3150 6075);
DISPLAY 0.489362 (-3150 6075);
PAINT SKYBLUE (-3150 6075);
FORCEPROP 1 LAST VALUE 0.1UF
J 0
(-3150 6175);
DISPLAY 0.489362 (-3150 6175);
PAINT SKYBLUE (-3150 6175);
FORCEPROP 1 LAST PART_NUMBER CH4104K1B00
J 0
(-3150 5975);
DISPLAY 0.489362 (-3150 5975);
PAINT SKYBLUE (-3150 5975);
FORCEPROP 1 LAST VOLTAGE 25V
J 0
(-3150 6125);
DISPLAY 0.489362 (-3150 6125);
PAINT SKYBLUE (-3150 6125);
FORCEPROP 1 LAST PACK_TYPE 0402
J 0
(-3150 5925);
DISPLAY 0.489362 (-3150 5925);
PAINT SKYBLUE (-3150 5925);
FORCEPROP 2 LAST CDS_LIB pure_quanta
J 0
(-3200 6125);
DISPLAY INVISIBLE (-3200 6125);
FORCEPROP 1 LAST PATH I156
J 0
(-3150 6275);
DISPLAY 0.978723 (-3150 6275);
PAINT WHITE (-3150 6275);
DISPLAY INVISIBLE (-3150 6275);
FORCEADD UNIVERSAL_GND..1
(-3200 5425);
FORCEPROP 3 LASTPIN (-3200 5475) SIG_NAME GND\g
J 0
(-3190 5485);
DISPLAY 0.659574 (-3190 5485);
PAINT MONO (-3190 5485);
DISPLAY INVISIBLE (-3190 5485);
FORCEPROP 2 LAST CDS_LIB pure_quanta_power
J 0
(-3200 5425);
DISPLAY INVISIBLE (-3200 5425);
FORCEPROP 1 LAST PATH I157
J 0
(-3125 5425);
DISPLAY 0.872340 (-3125 5425);
PAINT AQUA (-3125 5425);
DISPLAY INVISIBLE (-3125 5425);
FORCEPROP 1 LAST HDL_POWER GND
J 1
(-3175 5350);
DISPLAY 0.872340 (-3175 5350);
PAINT GREEN (-3175 5350);
DISPLAY INVISIBLE (-3175 5350);
FORCEADD Q_CAP..1
(-3200 5650);
FORCEPROP 1 LAST LOCATION PC13
J 0
(-3150 5750);
DISPLAY 0.489362 (-3150 5750);
PAINT SKYBLUE (-3150 5750);
FORCEPROP 0 LAST $SEC 1
J 0
(-3150 5775);
DISPLAY 0.680851 (-3150 5775);
PAINT MONO (-3150 5775);
DISPLAY INVISIBLE (-3150 5775);
FORCEPROP 0 LAST CDS_SEC 1
J 0
(-3150 5775);
DISPLAY 1.021277 (-3150 5775);
DISPLAY INVISIBLE (-3150 5775);
FORCEPROP 1 LASTPIN (-3200 5750) $PN 1
J 0
(-3190 5730);
DISPLAY 0.489362 (-3190 5730);
PAINT MONO (-3190 5730);
FORCEPROP 1 LASTPIN (-3200 5550) $PN 2
J 0
(-3190 5530);
DISPLAY 0.489362 (-3190 5530);
PAINT MONO (-3190 5530);
FORCEPROP 1 LAST MATERIAL X7R
J 0
(-3150 5550);
DISPLAY 0.489362 (-3150 5550);
PAINT SKYBLUE (-3150 5550);
FORCEPROP 1 LAST TOLERANCE 10%
J 0
(-3150 5600);
DISPLAY 0.489362 (-3150 5600);
PAINT SKYBLUE (-3150 5600);
FORCEPROP 1 LAST VALUE 0.1UF
J 0
(-3150 5700);
DISPLAY 0.489362 (-3150 5700);
PAINT SKYBLUE (-3150 5700);
FORCEPROP 1 LAST PART_NUMBER CH4104K1B00
J 0
(-3150 5500);
DISPLAY 0.489362 (-3150 5500);
PAINT SKYBLUE (-3150 5500);
FORCEPROP 1 LAST VOLTAGE 25V
J 0
(-3150 5650);
DISPLAY 0.489362 (-3150 5650);
PAINT SKYBLUE (-3150 5650);
FORCEPROP 1 LAST PACK_TYPE 0402
J 0
(-3150 5450);
DISPLAY 0.489362 (-3150 5450);
PAINT SKYBLUE (-3150 5450);
FORCEPROP 2 LAST CDS_LIB pure_quanta
J 0
(-3200 5650);
DISPLAY INVISIBLE (-3200 5650);
FORCEPROP 1 LAST PATH I158
J 0
(-3150 5800);
DISPLAY 0.978723 (-3150 5800);
PAINT WHITE (-3150 5800);
DISPLAY INVISIBLE (-3150 5800);
FORCEADD OFFPAGE..1
(-6700 2250);
FORCEPROP 2 LAST $XR0 77 
J 0
(-6951 2250);
DISPLAY 0.638298 (-6951 2250);
PAINT MONO (-6951 2250);
FORCEPROP 2 LAST CDS_LIB standard
J 0
(-6700 2250);
DISPLAY INVISIBLE (-6700 2250);
FORCEPROP 1 LAST OFFPAGE TRUE
J 0
(-6375 2125);
DISPLAY 0.872340 (-6375 2125);
PAINT GREEN (-6375 2125);
DISPLAY INVISIBLE (-6375 2125);
FORCEPROP 1 LAST COMMENT_BODY TRUE
J 0
(-6575 2150);
DISPLAY 0.872340 (-6575 2150);
PAINT GREEN (-6575 2150);
DISPLAY INVISIBLE (-6575 2150);
FORCEPROP 2 LAST PATH I167
J 0
(-6650 2325);
DISPLAY 1.021277 (-6650 2325);
DISPLAY INVISIBLE (-6650 2325);
FORCEADD VCC_CORE..1
(-6275 1800);
FORCEPROP 3 LASTPIN (-6275 1750) SIG_NAME PVDD18_S5_P0\g
J 0
(-6265 1760);
DISPLAY 0.659574 (-6265 1760);
PAINT MONO (-6265 1760);
DISPLAY INVISIBLE (-6265 1760);
FORCEPROP 1 LAST HDL_POWER PVDD18_S5_P0
J 1
(-6275 1850);
DISPLAY 0.489362 (-6275 1850);
PAINT GREEN (-6275 1850);
FORCEPROP 2 LAST CDS_LIB pure_quanta_power
J 0
(-6275 1800);
DISPLAY INVISIBLE (-6275 1800);
FORCEPROP 1 LAST PATH I168
J 0
(-6225 1825);
DISPLAY 0.872340 (-6225 1825);
PAINT AQUA (-6225 1825);
DISPLAY INVISIBLE (-6225 1825);
FORCEADD UNIVERSAL_GND..1
R 1
(-5275 1725);
FORCEPROP 3 LASTPIN (-5325 1725) SIG_NAME GND\g
J 0
(-5315 1735);
DISPLAY 0.659574 (-5315 1735);
PAINT MONO (-5315 1735);
DISPLAY INVISIBLE (-5315 1735);
FORCEPROP 2 LAST CDS_LIB pure_quanta_power
J 0
(-5275 1725);
DISPLAY INVISIBLE (-5275 1725);
FORCEPROP 1 LAST PATH I169
R 1
J 0
(-5275 1800);
DISPLAY 0.872340 (-5275 1800);
PAINT AQUA (-5275 1800);
DISPLAY INVISIBLE (-5275 1800);
FORCEPROP 1 LAST HDL_POWER GND
R 1
J 1
(-5200 1750);
DISPLAY 0.872340 (-5200 1750);
PAINT GREEN (-5200 1750);
DISPLAY INVISIBLE (-5200 1750);
FORCEADD Q_CAP..2
(-5675 1725);
FORCEPROP 1 LAST LOCATION PC466
J 1
(-6000 1775);
DISPLAY 0.489362 (-6000 1775);
PAINT SKYBLUE (-6000 1775);
FORCEPROP 0 LAST $SEC 1
J 0
(-5100 1800);
DISPLAY 0.680851 (-5100 1800);
PAINT MONO (-5100 1800);
DISPLAY INVISIBLE (-5100 1800);
FORCEPROP 0 LAST CDS_SEC 1
J 0
(-5100 1800);
DISPLAY 1.021277 (-5100 1800);
DISPLAY INVISIBLE (-5100 1800);
FORCEPROP 1 LASTPIN (-5775 1725) $PN 1
J 0
(-5785 1740);
DISPLAY 0.489362 (-5785 1740);
PAINT MONO (-5785 1740);
FORCEPROP 1 LASTPIN (-5575 1725) $PN 2
J 0
(-5590 1740);
DISPLAY 0.489362 (-5590 1740);
PAINT MONO (-5590 1740);
FORCEPROP 1 LAST PART_NUMBER CH5101K1B01
J 1
(-5450 1775);
DISPLAY 0.489362 (-5450 1775);
PAINT SKYBLUE (-5450 1775);
FORCEPROP 1 LAST MATERIAL X7R
J 0
(-5700 1775);
DISPLAY 0.489362 (-5700 1775);
PAINT SKYBLUE (-5700 1775);
FORCEPROP 1 LAST TOLERANCE 10%
J 2
(-5100 1775);
DISPLAY 0.489362 (-5100 1775);
PAINT SKYBLUE (-5100 1775);
FORCEPROP 1 LAST VALUE 1UF
J 2
(-5875 1775);
DISPLAY 0.489362 (-5875 1775);
PAINT SKYBLUE (-5875 1775);
FORCEPROP 1 LAST VOLTAGE 6.3V
J 0
(-5825 1775);
DISPLAY 0.489362 (-5825 1775);
PAINT SKYBLUE (-5825 1775);
FORCEPROP 1 LAST PACK_TYPE 0402
J 1
(-5250 1775);
DISPLAY 0.489362 (-5250 1775);
PAINT SKYBLUE (-5250 1775);
FORCEPROP 2 LAST CDS_LIB pure_quanta
J 0
(-5675 1725);
DISPLAY INVISIBLE (-5675 1725);
FORCEPROP 1 LAST PATH I170
J 0
(-5675 1925);
DISPLAY 0.978723 (-5675 1925);
PAINT WHITE (-5675 1925);
DISPLAY INVISIBLE (-5675 1925);
FORCEADD OFFPAGE..5
(-6700 2100);
FORCEPROP 2 LAST $XR0 81 
J 0
(-6954 2100);
DISPLAY 0.638298 (-6954 2100);
PAINT MONO (-6954 2100);
FORCEPROP 2 LAST CDS_LIB standard
J 0
(-6700 2100);
DISPLAY INVISIBLE (-6700 2100);
FORCEPROP 1 LAST OFFPAGE TRUE
J 0
(-6375 1975);
DISPLAY 0.872340 (-6375 1975);
PAINT GREEN (-6375 1975);
DISPLAY INVISIBLE (-6375 1975);
FORCEPROP 1 LAST COMMENT_BODY TRUE
J 0
(-6600 2025);
DISPLAY 0.872340 (-6600 2025);
PAINT GREEN (-6600 2025);
DISPLAY INVISIBLE (-6600 2025);
FORCEPROP 2 LAST PATH I171
J 0
(-6650 2175);
DISPLAY 1.021277 (-6650 2175);
DISPLAY INVISIBLE (-6650 2175);
FORCEADD VCC_CORE..1
(-6575 2525);
FORCEPROP 3 LASTPIN (-6575 2475) SIG_NAME PVDD18_S5_P0\g
J 0
(-6565 2485);
DISPLAY 0.659574 (-6565 2485);
PAINT MONO (-6565 2485);
DISPLAY INVISIBLE (-6565 2485);
FORCEPROP 1 LAST HDL_POWER PVDD18_S5_P0
J 1
(-6575 2575);
DISPLAY 0.489362 (-6575 2575);
PAINT GREEN (-6575 2575);
FORCEPROP 2 LAST CDS_LIB pure_quanta_power
J 0
(-6575 2525);
DISPLAY INVISIBLE (-6575 2525);
FORCEPROP 1 LAST PATH I172
J 0
(-6525 2550);
DISPLAY 0.872340 (-6525 2550);
PAINT AQUA (-6525 2550);
DISPLAY INVISIBLE (-6525 2550);
FORCEADD Q_RES..1
(-5975 2100);
FORCEPROP 1 LAST LOCATION PR301
J 0
(-6025 2150);
DISPLAY 0.489362 (-6025 2150);
PAINT SKYBLUE (-6025 2150);
FORCEPROP 0 LAST $SEC 1
J 0
(-6025 2175);
DISPLAY 0.680851 (-6025 2175);
PAINT MONO (-6025 2175);
DISPLAY INVISIBLE (-6025 2175);
FORCEPROP 0 LAST CDS_SEC 1
J 0
(-6025 2175);
DISPLAY 1.021277 (-6025 2175);
DISPLAY INVISIBLE (-6025 2175);
FORCEPROP 1 LASTPIN (-6075 2100) $PN 1
J 0
(-6063 2112);
DISPLAY 0.489362 (-6063 2112);
PAINT MONO (-6063 2112);
FORCEPROP 1 LASTPIN (-5875 2100) $PN 2
J 0
(-5913 2112);
DISPLAY 0.489362 (-5913 2112);
PAINT MONO (-5913 2112);
FORCEPROP 1 LAST WATTAGE 1/16W
J 2
(-6050 2050);
DISPLAY 0.489362 (-6050 2050);
PAINT SKYBLUE (-6050 2050);
FORCEPROP 1 LAST MATERIAL CHIP
J 0
(-6300 2050);
DISPLAY 0.489362 (-6300 2050);
PAINT SKYBLUE (-6300 2050);
FORCEPROP 1 LAST TOLERANCE 5%
J 0
(-5950 2050);
DISPLAY 0.489362 (-5950 2050);
PAINT SKYBLUE (-5950 2050);
FORCEPROP 1 LAST VALUE 0
J 2
(-5975 2050);
DISPLAY 0.489362 (-5975 2050);
PAINT SKYBLUE (-5975 2050);
FORCEPROP 1 LAST PART_NUMBER CS00002JB38
J 0
(-6650 2050);
DISPLAY 0.489362 (-6650 2050);
PAINT SKYBLUE (-6650 2050);
FORCEPROP 1 LAST PACK_TYPE 0402LF
J 0
(-5875 2050);
DISPLAY 0.489362 (-5875 2050);
PAINT SKYBLUE (-5875 2050);
FORCEPROP 2 LAST CDS_LIB pure_quanta
J 0
(-5975 2100);
DISPLAY INVISIBLE (-5975 2100);
FORCEPROP 1 LAST PATH I173
J 0
(-6025 2250);
DISPLAY 0.978723 (-6025 2250);
PAINT WHITE (-6025 2250);
DISPLAY INVISIBLE (-6025 2250);
FORCEADD Q_RES..1
(-5975 2250);
FORCEPROP 1 LAST LOCATION PR315
J 0
(-6025 2300);
DISPLAY 0.489362 (-6025 2300);
PAINT SKYBLUE (-6025 2300);
FORCEPROP 0 LAST $SEC 1
J 0
(-6025 2325);
DISPLAY 0.680851 (-6025 2325);
PAINT MONO (-6025 2325);
DISPLAY INVISIBLE (-6025 2325);
FORCEPROP 0 LAST CDS_SEC 1
J 0
(-6025 2325);
DISPLAY 1.021277 (-6025 2325);
DISPLAY INVISIBLE (-6025 2325);
FORCEPROP 1 LASTPIN (-6075 2250) $PN 1
J 0
(-6063 2262);
DISPLAY 0.489362 (-6063 2262);
PAINT MONO (-6063 2262);
FORCEPROP 1 LASTPIN (-5875 2250) $PN 2
J 0
(-5913 2262);
DISPLAY 0.489362 (-5913 2262);
PAINT MONO (-5913 2262);
FORCEPROP 1 LAST WATTAGE 1/16W
J 2
(-6050 2200);
DISPLAY 0.489362 (-6050 2200);
PAINT SKYBLUE (-6050 2200);
FORCEPROP 1 LAST MATERIAL CHIP
J 0
(-6300 2200);
DISPLAY 0.489362 (-6300 2200);
PAINT SKYBLUE (-6300 2200);
FORCEPROP 1 LAST TOLERANCE 5%
J 0
(-5950 2200);
DISPLAY 0.489362 (-5950 2200);
PAINT SKYBLUE (-5950 2200);
FORCEPROP 1 LAST VALUE 0
J 2
(-5975 2200);
DISPLAY 0.489362 (-5975 2200);
PAINT SKYBLUE (-5975 2200);
FORCEPROP 1 LAST PART_NUMBER CS00002JB38
J 0
(-6650 2200);
DISPLAY 0.489362 (-6650 2200);
PAINT SKYBLUE (-6650 2200);
FORCEPROP 1 LAST PACK_TYPE 0402LF
J 0
(-5875 2200);
DISPLAY 0.489362 (-5875 2200);
PAINT SKYBLUE (-5875 2200);
FORCEPROP 2 LAST CDS_LIB pure_quanta
J 0
(-5975 2250);
DISPLAY INVISIBLE (-5975 2250);
FORCEPROP 1 LAST PATH I174
J 0
(-6025 2400);
DISPLAY 0.978723 (-6025 2400);
PAINT WHITE (-6025 2400);
DISPLAY INVISIBLE (-6025 2400);
FORCEADD Q_RES..1
(-6125 2400);
FORCEPROP 1 LAST LOCATION PR317
J 0
(-6500 2425);
DISPLAY 0.489362 (-6500 2425);
PAINT SKYBLUE (-6500 2425);
FORCEPROP 0 LAST $SEC 1
J 0
(-6375 2500);
DISPLAY 0.680851 (-6375 2500);
PAINT MONO (-6375 2500);
DISPLAY INVISIBLE (-6375 2500);
FORCEPROP 0 LAST CDS_SEC 1
J 0
(-6375 2500);
DISPLAY 1.021277 (-6375 2500);
DISPLAY INVISIBLE (-6375 2500);
FORCEPROP 1 LASTPIN (-6225 2400) $PN 1
J 0
(-6213 2412);
DISPLAY 0.489362 (-6213 2412);
PAINT MONO (-6213 2412);
FORCEPROP 1 LASTPIN (-6025 2400) $PN 2
J 0
(-6063 2412);
DISPLAY 0.489362 (-6063 2412);
PAINT MONO (-6063 2412);
FORCEPROP 1 LAST WATTAGE 1/16W
J 2
(-5850 2425);
DISPLAY 0.489362 (-5850 2425);
PAINT SKYBLUE (-5850 2425);
FORCEPROP 1 LAST MATERIAL CHIP
J 0
(-6075 2425);
DISPLAY 0.489362 (-6075 2425);
PAINT SKYBLUE (-6075 2425);
FORCEPROP 1 LAST TOLERANCE 1%
J 0
(-6300 2425);
DISPLAY 0.489362 (-6300 2425);
PAINT SKYBLUE (-6300 2425);
FORCEPROP 1 LAST VALUE 1K
J 2
(-6325 2425);
DISPLAY 0.489362 (-6325 2425);
PAINT SKYBLUE (-6325 2425);
FORCEPROP 1 LAST PART_NUMBER TMP_QCS21002FB24
J 0
(-6375 2475);
DISPLAY 0.489362 (-6375 2475);
PAINT SKYBLUE (-6375 2475);
FORCEPROP 1 LAST PACK_TYPE 0402LF
J 0
(-6225 2425);
DISPLAY 0.489362 (-6225 2425);
PAINT SKYBLUE (-6225 2425);
FORCEPROP 2 LAST CDS_LIB pure_quanta
J 0
(-6125 2400);
DISPLAY INVISIBLE (-6125 2400);
FORCEPROP 1 LAST PATH I175
J 0
(-6175 2550);
DISPLAY 0.978723 (-6175 2550);
PAINT WHITE (-6175 2550);
DISPLAY INVISIBLE (-6175 2550);
FORCEADD Q_RES..1
(-5425 1975);
FORCEPROP 1 LAST LOCATION PR313
J 0
(-5475 1925);
DISPLAY 0.489362 (-5475 1925);
PAINT SKYBLUE (-5475 1925);
FORCEPROP 0 LAST $SEC 1
J 0
(-5675 2075);
DISPLAY 0.680851 (-5675 2075);
PAINT MONO (-5675 2075);
DISPLAY INVISIBLE (-5675 2075);
FORCEPROP 0 LAST CDS_SEC 1
J 0
(-5675 2075);
DISPLAY 1.021277 (-5675 2075);
DISPLAY INVISIBLE (-5675 2075);
FORCEPROP 1 LASTPIN (-5525 1975) $PN 1
J 0
(-5513 1987);
DISPLAY 0.489362 (-5513 1987);
PAINT MONO (-5513 1987);
FORCEPROP 1 LASTPIN (-5325 1975) $PN 2
J 0
(-5363 1987);
DISPLAY 0.489362 (-5363 1987);
PAINT MONO (-5363 1987);
FORCEPROP 1 LAST WATTAGE 1/16W
J 2
(-5150 2000);
DISPLAY 0.489362 (-5150 2000);
PAINT SKYBLUE (-5150 2000);
FORCEPROP 1 LAST MATERIAL CHIP
J 0
(-5375 2000);
DISPLAY 0.489362 (-5375 2000);
PAINT SKYBLUE (-5375 2000);
FORCEPROP 1 LAST TOLERANCE 1%
J 0
(-5600 2000);
DISPLAY 0.489362 (-5600 2000);
PAINT SKYBLUE (-5600 2000);
FORCEPROP 1 LAST VALUE 1K
J 2
(-5625 2000);
DISPLAY 0.489362 (-5625 2000);
PAINT SKYBLUE (-5625 2000);
FORCEPROP 1 LAST PART_NUMBER TMP_QCS21002FB24
J 0
(-5675 2050);
DISPLAY 0.489362 (-5675 2050);
PAINT SKYBLUE (-5675 2050);
FORCEPROP 1 LAST PACK_TYPE 0402LF
J 0
(-5525 2000);
DISPLAY 0.489362 (-5525 2000);
PAINT SKYBLUE (-5525 2000);
FORCEPROP 2 LAST CDS_LIB pure_quanta
J 0
(-5425 1975);
DISPLAY INVISIBLE (-5425 1975);
FORCEPROP 1 LAST PATH I176
J 0
(-5475 2125);
DISPLAY 0.978723 (-5475 2125);
PAINT WHITE (-5475 2125);
DISPLAY INVISIBLE (-5475 2125);
FORCEADD OFFPAGE..4
R 2
(-8850 5650);
FORCEPROP 2 LAST $XR0 27 
J 0
(-9071 5650);
DISPLAY 0.638298 (-9071 5650);
PAINT MONO (-9071 5650);
FORCEPROP 2 LAST CDS_LIB standard
J 0
(-8850 5650);
DISPLAY INVISIBLE (-8850 5650);
FORCEPROP 1 LAST OFFPAGE TRUE
J 2
(-9175 5525);
DISPLAY 0.872340 (-9175 5525);
PAINT GREEN (-9175 5525);
DISPLAY INVISIBLE (-9175 5525);
FORCEPROP 1 LAST COMMENT_BODY TRUE
J 2
(-8825 5550);
DISPLAY 0.872340 (-8825 5550);
PAINT GREEN (-8825 5550);
DISPLAY INVISIBLE (-8825 5550);
FORCEPROP 2 LAST PATH I183
J 0
(-8800 5725);
DISPLAY 1.021277 (-8800 5725);
DISPLAY INVISIBLE (-8800 5725);
FORCEADD OFFPAGE..4
R 2
(-8850 5500);
FORCEPROP 2 LAST $XR0 27 
J 0
(-9071 5500);
DISPLAY 0.638298 (-9071 5500);
PAINT MONO (-9071 5500);
FORCEPROP 2 LAST CDS_LIB standard
J 0
(-8850 5500);
DISPLAY INVISIBLE (-8850 5500);
FORCEPROP 1 LAST OFFPAGE TRUE
J 2
(-9175 5375);
DISPLAY 0.872340 (-9175 5375);
PAINT GREEN (-9175 5375);
DISPLAY INVISIBLE (-9175 5375);
FORCEPROP 1 LAST COMMENT_BODY TRUE
J 2
(-8825 5400);
DISPLAY 0.872340 (-8825 5400);
PAINT GREEN (-8825 5400);
DISPLAY INVISIBLE (-8825 5400);
FORCEPROP 2 LAST PATH I186
J 0
(-8800 5575);
DISPLAY 1.021277 (-8800 5575);
DISPLAY INVISIBLE (-8800 5575);
FORCEADD OFFPAGE..2
R 2
(-8850 5350);
FORCEPROP 2 LAST $XR0 27 
J 0
(-9104 5350);
DISPLAY 0.638298 (-9104 5350);
PAINT MONO (-9104 5350);
FORCEPROP 2 LAST CDS_LIB standard
J 0
(-8850 5350);
DISPLAY INVISIBLE (-8850 5350);
FORCEPROP 1 LAST OFFPAGE TRUE
J 2
(-9175 5225);
DISPLAY 0.872340 (-9175 5225);
PAINT GREEN (-9175 5225);
DISPLAY INVISIBLE (-9175 5225);
FORCEPROP 1 LAST COMMENT_BODY TRUE
J 2
(-8805 5255);
DISPLAY 0.872340 (-8805 5255);
PAINT GREEN (-8805 5255);
DISPLAY INVISIBLE (-8805 5255);
FORCEPROP 2 LAST PATH I187
J 0
(-8800 5425);
DISPLAY 1.021277 (-8800 5425);
DISPLAY INVISIBLE (-8800 5425);
FORCEADD Q_CAP..1
(-7600 5025);
FORCEPROP 1 LAST LOCATION PC302
J 0
(-7550 5125);
DISPLAY 0.489362 (-7550 5125);
PAINT SKYBLUE (-7550 5125);
FORCEPROP 0 LAST $SEC 1
J 0
(-7550 5150);
DISPLAY 0.680851 (-7550 5150);
PAINT MONO (-7550 5150);
DISPLAY INVISIBLE (-7550 5150);
FORCEPROP 0 LAST CDS_SEC 1
J 0
(-7550 5150);
DISPLAY 1.021277 (-7550 5150);
DISPLAY INVISIBLE (-7550 5150);
FORCEPROP 1 LASTPIN (-7600 5125) $PN 1
J 0
(-7590 5105);
DISPLAY 0.489362 (-7590 5105);
PAINT MONO (-7590 5105);
FORCEPROP 1 LASTPIN (-7600 4925) $PN 2
J 0
(-7590 4905);
DISPLAY 0.489362 (-7590 4905);
PAINT MONO (-7590 4905);
FORCEPROP 1 LAST PACK_TYPE 0402
J 0
(-7550 4825);
DISPLAY 0.489362 (-7550 4825);
PAINT SKYBLUE (-7550 4825);
FORCEPROP 1 LAST PART_NUMBER CH01006JB08
J 0
(-7550 4875);
DISPLAY 0.489362 (-7550 4875);
PAINT SKYBLUE (-7550 4875);
FORCEPROP 1 LAST MATERIAL EMPTY
J 0
(-7550 4925);
DISPLAY 0.489362 (-7550 4925);
PAINT RED (-7550 4925);
FORCEPROP 1 LAST TOLERANCE 5%
J 0
(-7550 4975);
DISPLAY 0.489362 (-7550 4975);
PAINT SKYBLUE (-7550 4975);
FORCEPROP 1 LAST VALUE 10PF
J 0
(-7550 5075);
DISPLAY 0.489362 (-7550 5075);
PAINT SKYBLUE (-7550 5075);
FORCEPROP 1 LAST VOLTAGE 50V
J 0
(-7550 5025);
DISPLAY 0.489362 (-7550 5025);
PAINT SKYBLUE (-7550 5025);
FORCEPROP 2 LAST CDS_LIB pure_quanta
J 0
(-7600 5025);
DISPLAY INVISIBLE (-7600 5025);
FORCEPROP 1 LAST PATH I214
J 0
(-7550 5175);
DISPLAY 0.978723 (-7550 5175);
PAINT WHITE (-7550 5175);
DISPLAY INVISIBLE (-7550 5175);
FORCEADD Q_CAP..1
(-7825 5025);
FORCEPROP 1 LAST LOCATION PC299
J 0
(-7775 5125);
DISPLAY 0.489362 (-7775 5125);
PAINT SKYBLUE (-7775 5125);
FORCEPROP 0 LAST $SEC 1
J 0
(-7775 5150);
DISPLAY 0.680851 (-7775 5150);
PAINT MONO (-7775 5150);
DISPLAY INVISIBLE (-7775 5150);
FORCEPROP 0 LAST CDS_SEC 1
J 0
(-7775 5150);
DISPLAY 1.021277 (-7775 5150);
DISPLAY INVISIBLE (-7775 5150);
FORCEPROP 1 LASTPIN (-7825 5125) $PN 1
J 0
(-7815 5105);
DISPLAY 0.489362 (-7815 5105);
PAINT MONO (-7815 5105);
FORCEPROP 1 LASTPIN (-7825 4925) $PN 2
J 0
(-7815 4905);
DISPLAY 0.489362 (-7815 4905);
PAINT MONO (-7815 4905);
FORCEPROP 1 LAST VOLTAGE 50V
J 0
(-7775 5025);
DISPLAY 0.489362 (-7775 5025);
PAINT SKYBLUE (-7775 5025);
FORCEPROP 1 LAST MATERIAL EMPTY
J 0
(-7775 4925);
DISPLAY 0.489362 (-7775 4925);
PAINT RED (-7775 4925);
FORCEPROP 1 LAST TOLERANCE 5%
J 0
(-7775 4975);
DISPLAY 0.489362 (-7775 4975);
PAINT SKYBLUE (-7775 4975);
FORCEPROP 1 LAST PACK_TYPE 0402
J 0
(-7775 4825);
DISPLAY 0.489362 (-7775 4825);
PAINT SKYBLUE (-7775 4825);
FORCEPROP 1 LAST VALUE 10PF
J 0
(-7775 5075);
DISPLAY 0.489362 (-7775 5075);
PAINT SKYBLUE (-7775 5075);
FORCEPROP 2 LAST CDS_LIB pure_quanta
J 0
(-7825 5025);
DISPLAY INVISIBLE (-7825 5025);
FORCEPROP 1 LAST PATH I215
J 0
(-7775 5175);
DISPLAY 0.978723 (-7775 5175);
PAINT WHITE (-7775 5175);
DISPLAY INVISIBLE (-7775 5175);
FORCEPROP 1 LAST PART_NUMBER CH01006JB08
J 0
(-7775 4875);
DISPLAY 0.489362 (-7775 4875);
PAINT SKYBLUE (-7775 4875);
DISPLAY INVISIBLE (-7775 4875);
FORCEADD Q_CAP..1
(-8050 5025);
FORCEPROP 1 LAST LOCATION PC298
J 0
(-8000 5125);
DISPLAY 0.489362 (-8000 5125);
PAINT SKYBLUE (-8000 5125);
FORCEPROP 0 LAST $SEC 1
J 0
(-8000 5150);
DISPLAY 0.680851 (-8000 5150);
PAINT MONO (-8000 5150);
DISPLAY INVISIBLE (-8000 5150);
FORCEPROP 0 LAST CDS_SEC 1
J 0
(-8000 5150);
DISPLAY 1.021277 (-8000 5150);
DISPLAY INVISIBLE (-8000 5150);
FORCEPROP 1 LASTPIN (-8050 5125) $PN 1
J 0
(-8040 5105);
DISPLAY 0.489362 (-8040 5105);
PAINT MONO (-8040 5105);
FORCEPROP 1 LASTPIN (-8050 4925) $PN 2
J 0
(-8040 4905);
DISPLAY 0.489362 (-8040 4905);
PAINT MONO (-8040 4905);
FORCEPROP 1 LAST MATERIAL EMPTY
J 0
(-8000 4925);
DISPLAY 0.489362 (-8000 4925);
PAINT RED (-8000 4925);
FORCEPROP 1 LAST TOLERANCE 5%
J 0
(-8000 4975);
DISPLAY 0.489362 (-8000 4975);
PAINT SKYBLUE (-8000 4975);
FORCEPROP 1 LAST VALUE 10PF
J 0
(-8000 5075);
DISPLAY 0.489362 (-8000 5075);
PAINT SKYBLUE (-8000 5075);
FORCEPROP 1 LAST VOLTAGE 50V
J 0
(-8000 5025);
DISPLAY 0.489362 (-8000 5025);
PAINT SKYBLUE (-8000 5025);
FORCEPROP 1 LAST PACK_TYPE 0402
J 0
(-8000 4825);
DISPLAY 0.489362 (-8000 4825);
PAINT SKYBLUE (-8000 4825);
FORCEPROP 2 LAST CDS_LIB pure_quanta
J 0
(-8050 5025);
DISPLAY INVISIBLE (-8050 5025);
FORCEPROP 1 LAST PATH I216
J 0
(-8000 5175);
DISPLAY 0.978723 (-8000 5175);
PAINT WHITE (-8000 5175);
DISPLAY INVISIBLE (-8000 5175);
FORCEPROP 1 LAST PART_NUMBER CH01006JB08
J 0
(-8000 4875);
DISPLAY 0.489362 (-8000 4875);
PAINT SKYBLUE (-8000 4875);
DISPLAY INVISIBLE (-8000 4875);
FORCEADD UNIVERSAL_GND..1
(-8050 4775);
FORCEPROP 3 LASTPIN (-8050 4825) SIG_NAME GND\g
J 0
(-8040 4835);
DISPLAY 0.659574 (-8040 4835);
PAINT MONO (-8040 4835);
DISPLAY INVISIBLE (-8040 4835);
FORCEPROP 2 LAST CDS_LIB pure_quanta_power
J 0
(-8050 4775);
DISPLAY INVISIBLE (-8050 4775);
FORCEPROP 1 LAST PATH I217
J 0
(-7975 4775);
DISPLAY 0.872340 (-7975 4775);
PAINT AQUA (-7975 4775);
DISPLAY INVISIBLE (-7975 4775);
FORCEPROP 1 LAST HDL_POWER GND
J 1
(-8025 4700);
DISPLAY 0.872340 (-8025 4700);
PAINT GREEN (-8025 4700);
DISPLAY INVISIBLE (-8025 4700);
FORCEADD OFFPAGE..2
(-2800 1800);
FORCEPROP 2 LAST $XR0 174 
J 0
(-2611 1800);
DISPLAY 0.638298 (-2611 1800);
PAINT MONO (-2611 1800);
FORCEPROP 2 LAST PATH I220
J 0
(-2600 1850);
DISPLAY 1.021277 (-2600 1850);
DISPLAY INVISIBLE (-2600 1850);
FORCEPROP 2 LAST CDS_LIB standard
J 0
(-2800 1800);
DISPLAY INVISIBLE (-2800 1800);
FORCEPROP 1 LAST OFFPAGE TRUE
J 0
(-2475 1675);
DISPLAY 0.872340 (-2475 1675);
PAINT GREEN (-2475 1675);
DISPLAY INVISIBLE (-2475 1675);
FORCEPROP 1 LAST COMMENT_BODY TRUE
J 0
(-2845 1705);
DISPLAY 0.872340 (-2845 1705);
PAINT GREEN (-2845 1705);
DISPLAY INVISIBLE (-2845 1705);
FORCEADD OFFPAGE..4
(-2800 1700);
FORCEPROP 2 LAST $XR0 174 
J 0
(-2614 1700);
DISPLAY 0.638298 (-2614 1700);
PAINT MONO (-2614 1700);
FORCEPROP 2 LAST PATH I221
J 0
(-2600 1750);
DISPLAY 1.021277 (-2600 1750);
DISPLAY INVISIBLE (-2600 1750);
FORCEPROP 2 LAST CDS_LIB standard
J 0
(-2800 1700);
DISPLAY INVISIBLE (-2800 1700);
FORCEPROP 1 LAST OFFPAGE TRUE
J 0
(-2475 1575);
DISPLAY 0.872340 (-2475 1575);
PAINT GREEN (-2475 1575);
DISPLAY INVISIBLE (-2475 1575);
FORCEPROP 1 LAST COMMENT_BODY TRUE
J 0
(-2825 1600);
DISPLAY 0.872340 (-2825 1600);
PAINT GREEN (-2825 1600);
DISPLAY INVISIBLE (-2825 1600);
FORCEADD OFFPAGE..2
(-2800 5100);
FORCEPROP 2 LAST $XR0 170 
J 0
(-2611 5100);
DISPLAY 0.638298 (-2611 5100);
PAINT MONO (-2611 5100);
FORCEPROP 2 LAST PATH I222
J 0
(-2600 5150);
DISPLAY 1.021277 (-2600 5150);
DISPLAY INVISIBLE (-2600 5150);
FORCEPROP 1 LAST COMMENT_BODY TRUE
J 0
(-2845 5005);
DISPLAY 0.872340 (-2845 5005);
PAINT GREEN (-2845 5005);
DISPLAY INVISIBLE (-2845 5005);
FORCEPROP 1 LAST OFFPAGE TRUE
J 0
(-2475 4975);
DISPLAY 0.872340 (-2475 4975);
PAINT GREEN (-2475 4975);
DISPLAY INVISIBLE (-2475 4975);
FORCEPROP 2 LAST CDS_LIB standard
J 0
(-2800 5100);
DISPLAY INVISIBLE (-2800 5100);
FORCEADD OFFPAGE..4
(-2800 5000);
FORCEPROP 2 LAST $XR0 170 
J 0
(-2614 5000);
DISPLAY 0.638298 (-2614 5000);
PAINT MONO (-2614 5000);
FORCEPROP 2 LAST PATH I223
J 0
(-2600 5050);
DISPLAY 1.021277 (-2600 5050);
DISPLAY INVISIBLE (-2600 5050);
FORCEPROP 1 LAST COMMENT_BODY TRUE
J 0
(-2825 4900);
DISPLAY 0.872340 (-2825 4900);
PAINT GREEN (-2825 4900);
DISPLAY INVISIBLE (-2825 4900);
FORCEPROP 1 LAST OFFPAGE TRUE
J 0
(-2475 4875);
DISPLAY 0.872340 (-2475 4875);
PAINT GREEN (-2475 4875);
DISPLAY INVISIBLE (-2475 4875);
FORCEPROP 2 LAST CDS_LIB standard
J 0
(-2800 5000);
DISPLAY INVISIBLE (-2800 5000);
FORCEADD OFFPAGE..4
(-2800 2000);
FORCEPROP 2 LAST $XR0 174 
J 0
(-2614 2000);
DISPLAY 0.638298 (-2614 2000);
PAINT MONO (-2614 2000);
FORCEPROP 2 LAST PATH I224
J 0
(-2600 2050);
DISPLAY 1.021277 (-2600 2050);
DISPLAY INVISIBLE (-2600 2050);
FORCEPROP 1 LAST COMMENT_BODY TRUE
J 0
(-2825 1900);
DISPLAY 0.872340 (-2825 1900);
PAINT GREEN (-2825 1900);
DISPLAY INVISIBLE (-2825 1900);
FORCEPROP 1 LAST OFFPAGE TRUE
J 0
(-2475 1875);
DISPLAY 0.872340 (-2475 1875);
PAINT GREEN (-2475 1875);
DISPLAY INVISIBLE (-2475 1875);
FORCEPROP 2 LAST CDS_LIB standard
J 0
(-2800 2000);
DISPLAY INVISIBLE (-2800 2000);
FORCEADD OFFPAGE..2
(-2800 2100);
FORCEPROP 2 LAST $XR0 174 
J 0
(-2611 2100);
DISPLAY 0.638298 (-2611 2100);
PAINT MONO (-2611 2100);
FORCEPROP 2 LAST PATH I225
J 0
(-2600 2150);
DISPLAY 1.021277 (-2600 2150);
DISPLAY INVISIBLE (-2600 2150);
FORCEPROP 1 LAST COMMENT_BODY TRUE
J 0
(-2845 2005);
DISPLAY 0.872340 (-2845 2005);
PAINT GREEN (-2845 2005);
DISPLAY INVISIBLE (-2845 2005);
FORCEPROP 1 LAST OFFPAGE TRUE
J 0
(-2475 1975);
DISPLAY 0.872340 (-2475 1975);
PAINT GREEN (-2475 1975);
DISPLAY INVISIBLE (-2475 1975);
FORCEPROP 2 LAST CDS_LIB standard
J 0
(-2800 2100);
DISPLAY INVISIBLE (-2800 2100);
FORCEADD OFFPAGE..2
(-2800 4800);
FORCEPROP 2 LAST $XR0 170 
J 0
(-2611 4800);
DISPLAY 0.638298 (-2611 4800);
PAINT MONO (-2611 4800);
FORCEPROP 2 LAST PATH I226
J 0
(-2600 4850);
DISPLAY 1.021277 (-2600 4850);
DISPLAY INVISIBLE (-2600 4850);
FORCEPROP 2 LAST CDS_LIB standard
J 0
(-2800 4800);
DISPLAY INVISIBLE (-2800 4800);
FORCEPROP 1 LAST OFFPAGE TRUE
J 0
(-2475 4675);
DISPLAY 0.872340 (-2475 4675);
PAINT GREEN (-2475 4675);
DISPLAY INVISIBLE (-2475 4675);
FORCEPROP 1 LAST COMMENT_BODY TRUE
J 0
(-2845 4705);
DISPLAY 0.872340 (-2845 4705);
PAINT GREEN (-2845 4705);
DISPLAY INVISIBLE (-2845 4705);
FORCEADD OFFPAGE..4
(-2800 4700);
FORCEPROP 2 LAST $XR0 170 
J 0
(-2614 4700);
DISPLAY 0.638298 (-2614 4700);
PAINT MONO (-2614 4700);
FORCEPROP 2 LAST PATH I227
J 0
(-2600 4750);
DISPLAY 1.021277 (-2600 4750);
DISPLAY INVISIBLE (-2600 4750);
FORCEPROP 2 LAST CDS_LIB standard
J 0
(-2800 4700);
DISPLAY INVISIBLE (-2800 4700);
FORCEPROP 1 LAST OFFPAGE TRUE
J 0
(-2475 4575);
DISPLAY 0.872340 (-2475 4575);
PAINT GREEN (-2475 4575);
DISPLAY INVISIBLE (-2475 4575);
FORCEPROP 1 LAST COMMENT_BODY TRUE
J 0
(-2825 4600);
DISPLAY 0.872340 (-2825 4600);
PAINT GREEN (-2825 4600);
DISPLAY INVISIBLE (-2825 4600);
FORCEADD OFFPAGE..2
(-2800 4500);
FORCEPROP 2 LAST $XR0 171 
J 0
(-2611 4500);
DISPLAY 0.638298 (-2611 4500);
PAINT MONO (-2611 4500);
FORCEPROP 2 LAST CDS_LIB standard
J 0
(-2800 4500);
DISPLAY INVISIBLE (-2800 4500);
FORCEPROP 1 LAST OFFPAGE TRUE
J 0
(-2475 4375);
DISPLAY 0.872340 (-2475 4375);
PAINT GREEN (-2475 4375);
DISPLAY INVISIBLE (-2475 4375);
FORCEPROP 1 LAST COMMENT_BODY TRUE
J 0
(-2845 4405);
DISPLAY 0.872340 (-2845 4405);
PAINT GREEN (-2845 4405);
DISPLAY INVISIBLE (-2845 4405);
FORCEPROP 2 LAST PATH I228
J 0
(-2600 4550);
DISPLAY 1.021277 (-2600 4550);
DISPLAY INVISIBLE (-2600 4550);
FORCEADD OFFPAGE..4
(-2800 4400);
FORCEPROP 2 LAST $XR0 171 
J 0
(-2614 4400);
DISPLAY 0.638298 (-2614 4400);
PAINT MONO (-2614 4400);
FORCEPROP 2 LAST CDS_LIB standard
J 0
(-2800 4400);
DISPLAY INVISIBLE (-2800 4400);
FORCEPROP 1 LAST OFFPAGE TRUE
J 0
(-2475 4275);
DISPLAY 0.872340 (-2475 4275);
PAINT GREEN (-2475 4275);
DISPLAY INVISIBLE (-2475 4275);
FORCEPROP 1 LAST COMMENT_BODY TRUE
J 0
(-2825 4300);
DISPLAY 0.872340 (-2825 4300);
PAINT GREEN (-2825 4300);
DISPLAY INVISIBLE (-2825 4300);
FORCEPROP 2 LAST PATH I229
J 0
(-2600 4450);
DISPLAY 1.021277 (-2600 4450);
DISPLAY INVISIBLE (-2600 4450);
FORCEADD OFFPAGE..4
(-2800 2300);
FORCEPROP 2 LAST $XR0 175 
J 0
(-2614 2300);
DISPLAY 0.638298 (-2614 2300);
PAINT MONO (-2614 2300);
FORCEPROP 2 LAST PATH I230
J 0
(-2600 2350);
DISPLAY 1.021277 (-2600 2350);
DISPLAY INVISIBLE (-2600 2350);
FORCEPROP 2 LAST CDS_LIB standard
J 0
(-2800 2300);
DISPLAY INVISIBLE (-2800 2300);
FORCEPROP 1 LAST OFFPAGE TRUE
J 0
(-2475 2175);
DISPLAY 0.872340 (-2475 2175);
PAINT GREEN (-2475 2175);
DISPLAY INVISIBLE (-2475 2175);
FORCEPROP 1 LAST COMMENT_BODY TRUE
J 0
(-2825 2200);
DISPLAY 0.872340 (-2825 2200);
PAINT GREEN (-2825 2200);
DISPLAY INVISIBLE (-2825 2200);
FORCEADD OFFPAGE..2
(-2800 2400);
FORCEPROP 2 LAST $XR0 175 
J 0
(-2611 2400);
DISPLAY 0.638298 (-2611 2400);
PAINT MONO (-2611 2400);
FORCEPROP 2 LAST PATH I231
J 0
(-2600 2450);
DISPLAY 1.021277 (-2600 2450);
DISPLAY INVISIBLE (-2600 2450);
FORCEPROP 2 LAST CDS_LIB standard
J 0
(-2800 2400);
DISPLAY INVISIBLE (-2800 2400);
FORCEPROP 1 LAST OFFPAGE TRUE
J 0
(-2475 2275);
DISPLAY 0.872340 (-2475 2275);
PAINT GREEN (-2475 2275);
DISPLAY INVISIBLE (-2475 2275);
FORCEPROP 1 LAST COMMENT_BODY TRUE
J 0
(-2845 2305);
DISPLAY 0.872340 (-2845 2305);
PAINT GREEN (-2845 2305);
DISPLAY INVISIBLE (-2845 2305);
FORCEADD Q_RES..1
(-2925 2900);
FORCEPROP 1 LAST LOCATION PR440
J 0
(-2975 2950);
DISPLAY 0.489362 (-2975 2950);
PAINT SKYBLUE (-2975 2950);
FORCEPROP 0 LAST $SEC 1
J 0
(-2975 2975);
DISPLAY 0.680851 (-2975 2975);
PAINT MONO (-2975 2975);
DISPLAY INVISIBLE (-2975 2975);
FORCEPROP 0 LAST CDS_SEC 1
J 0
(-2975 2975);
DISPLAY 1.021277 (-2975 2975);
DISPLAY INVISIBLE (-2975 2975);
FORCEPROP 1 LASTPIN (-3025 2900) $PN 1
J 0
(-3013 2912);
DISPLAY 0.489362 (-3013 2912);
PAINT MONO (-3013 2912);
FORCEPROP 1 LASTPIN (-2825 2900) $PN 2
J 0
(-2863 2912);
DISPLAY 0.489362 (-2863 2912);
PAINT MONO (-2863 2912);
FORCEPROP 1 LAST WATTAGE 1/16W
J 2
(-3000 2850);
DISPLAY 0.489362 (-3000 2850);
PAINT SKYBLUE (-3000 2850);
FORCEPROP 1 LAST VALUE 0
J 2
(-2925 2850);
DISPLAY 0.489362 (-2925 2850);
PAINT SKYBLUE (-2925 2850);
FORCEPROP 1 LAST TOLERANCE 5%
J 0
(-2900 2850);
DISPLAY 0.489362 (-2900 2850);
PAINT SKYBLUE (-2900 2850);
FORCEPROP 1 LAST PART_NUMBER CS00002JB38
J 0
(-3600 2850);
DISPLAY 0.489362 (-3600 2850);
PAINT SKYBLUE (-3600 2850);
FORCEPROP 1 LAST PACK_TYPE 0402LF
J 0
(-2825 2850);
DISPLAY 0.489362 (-2825 2850);
PAINT SKYBLUE (-2825 2850);
FORCEPROP 1 LAST MATERIAL CHIP
J 0
(-3250 2850);
DISPLAY 0.489362 (-3250 2850);
PAINT SKYBLUE (-3250 2850);
FORCEPROP 2 LAST CDS_LIB pure_quanta
J 0
(-2925 2900);
DISPLAY INVISIBLE (-2925 2900);
FORCEPROP 1 LAST PATH I232
J 0
(-2975 3050);
DISPLAY 0.978723 (-2975 3050);
PAINT WHITE (-2975 3050);
DISPLAY INVISIBLE (-2975 3050);
FORCEADD UNIVERSAL_GND..1
(-2575 2750);
FORCEPROP 3 LASTPIN (-2575 2800) SIG_NAME GND\g
J 0
(-2565 2810);
DISPLAY 0.659574 (-2565 2810);
PAINT MONO (-2565 2810);
DISPLAY INVISIBLE (-2565 2810);
FORCEPROP 2 LAST CDS_LIB pure_quanta_power
J 0
(-2575 2750);
DISPLAY INVISIBLE (-2575 2750);
FORCEPROP 1 LAST PATH I233
J 0
(-2500 2750);
DISPLAY 0.872340 (-2500 2750);
PAINT AQUA (-2500 2750);
DISPLAY INVISIBLE (-2500 2750);
FORCEPROP 1 LAST HDL_POWER GND
J 1
(-2550 2675);
DISPLAY 0.872340 (-2550 2675);
PAINT GREEN (-2550 2675);
DISPLAY INVISIBLE (-2550 2675);
FORCEADD UNIVERSAL_GND..1
(-2575 3050);
FORCEPROP 3 LASTPIN (-2575 3100) SIG_NAME GND\g
J 0
(-2565 3110);
DISPLAY 0.659574 (-2565 3110);
PAINT MONO (-2565 3110);
DISPLAY INVISIBLE (-2565 3110);
FORCEPROP 2 LAST CDS_LIB pure_quanta_power
J 0
(-2575 3050);
DISPLAY INVISIBLE (-2575 3050);
FORCEPROP 1 LAST PATH I234
J 0
(-2500 3050);
DISPLAY 0.872340 (-2500 3050);
PAINT AQUA (-2500 3050);
DISPLAY INVISIBLE (-2500 3050);
FORCEPROP 1 LAST HDL_POWER GND
J 1
(-2550 2975);
DISPLAY 0.872340 (-2550 2975);
PAINT GREEN (-2550 2975);
DISPLAY INVISIBLE (-2550 2975);
FORCEADD Q_RES..1
(-2925 3200);
FORCEPROP 1 LAST LOCATION PR531
J 0
(-2975 3250);
DISPLAY 0.489362 (-2975 3250);
PAINT SKYBLUE (-2975 3250);
FORCEPROP 0 LAST $SEC 1
J 0
(-2975 3275);
DISPLAY 0.680851 (-2975 3275);
PAINT MONO (-2975 3275);
DISPLAY INVISIBLE (-2975 3275);
FORCEPROP 0 LAST CDS_SEC 1
J 0
(-2975 3275);
DISPLAY 1.021277 (-2975 3275);
DISPLAY INVISIBLE (-2975 3275);
FORCEPROP 1 LASTPIN (-3025 3200) $PN 1
J 0
(-3013 3212);
DISPLAY 0.489362 (-3013 3212);
PAINT MONO (-3013 3212);
FORCEPROP 1 LASTPIN (-2825 3200) $PN 2
J 0
(-2863 3212);
DISPLAY 0.489362 (-2863 3212);
PAINT MONO (-2863 3212);
FORCEPROP 1 LAST PART_NUMBER CS00002JB38
J 0
(-3600 3150);
DISPLAY 0.489362 (-3600 3150);
PAINT SKYBLUE (-3600 3150);
FORCEPROP 1 LAST WATTAGE 1/16W
J 2
(-3000 3150);
DISPLAY 0.489362 (-3000 3150);
PAINT SKYBLUE (-3000 3150);
FORCEPROP 1 LAST MATERIAL CHIP
J 0
(-3250 3150);
DISPLAY 0.489362 (-3250 3150);
PAINT SKYBLUE (-3250 3150);
FORCEPROP 1 LAST VALUE 0
J 2
(-2925 3150);
DISPLAY 0.489362 (-2925 3150);
PAINT SKYBLUE (-2925 3150);
FORCEPROP 1 LAST TOLERANCE 5%
J 0
(-2900 3150);
DISPLAY 0.489362 (-2900 3150);
PAINT SKYBLUE (-2900 3150);
FORCEPROP 1 LAST PACK_TYPE 0402LF
J 0
(-2825 3150);
DISPLAY 0.489362 (-2825 3150);
PAINT SKYBLUE (-2825 3150);
FORCEPROP 2 LAST CDS_LIB pure_quanta
J 0
(-2925 3200);
DISPLAY INVISIBLE (-2925 3200);
FORCEPROP 1 LAST PATH I235
J 0
(-2975 3350);
DISPLAY 0.978723 (-2975 3350);
PAINT WHITE (-2975 3350);
DISPLAY INVISIBLE (-2975 3350);
FORCEADD OFFPAGE..2
(-2800 4200);
FORCEPROP 2 LAST $XR0 171 
J 0
(-2611 4200);
DISPLAY 0.638298 (-2611 4200);
PAINT MONO (-2611 4200);
FORCEPROP 2 LAST PATH I236
J 0
(-2600 4250);
DISPLAY 1.021277 (-2600 4250);
DISPLAY INVISIBLE (-2600 4250);
FORCEPROP 2 LAST CDS_LIB standard
J 0
(-2800 4200);
DISPLAY INVISIBLE (-2800 4200);
FORCEPROP 1 LAST OFFPAGE TRUE
J 0
(-2475 4075);
DISPLAY 0.872340 (-2475 4075);
PAINT GREEN (-2475 4075);
DISPLAY INVISIBLE (-2475 4075);
FORCEPROP 1 LAST COMMENT_BODY TRUE
J 0
(-2845 4105);
DISPLAY 0.872340 (-2845 4105);
PAINT GREEN (-2845 4105);
DISPLAY INVISIBLE (-2845 4105);
FORCEADD OFFPAGE..4
(-2800 4100);
FORCEPROP 2 LAST $XR0 171 
J 0
(-2614 4100);
DISPLAY 0.638298 (-2614 4100);
PAINT MONO (-2614 4100);
FORCEPROP 2 LAST PATH I237
J 0
(-2600 4150);
DISPLAY 1.021277 (-2600 4150);
DISPLAY INVISIBLE (-2600 4150);
FORCEPROP 2 LAST CDS_LIB standard
J 0
(-2800 4100);
DISPLAY INVISIBLE (-2800 4100);
FORCEPROP 1 LAST OFFPAGE TRUE
J 0
(-2475 3975);
DISPLAY 0.872340 (-2475 3975);
PAINT GREEN (-2475 3975);
DISPLAY INVISIBLE (-2475 3975);
FORCEPROP 1 LAST COMMENT_BODY TRUE
J 0
(-2825 4000);
DISPLAY 0.872340 (-2825 4000);
PAINT GREEN (-2825 4000);
DISPLAY INVISIBLE (-2825 4000);
FORCEADD OFFPAGE..4
(-2800 3800);
FORCEPROP 2 LAST $XR0 172 
J 0
(-2614 3800);
DISPLAY 0.638298 (-2614 3800);
PAINT MONO (-2614 3800);
FORCEPROP 2 LAST PATH I238
J 0
(-2600 3850);
DISPLAY 1.021277 (-2600 3850);
DISPLAY INVISIBLE (-2600 3850);
FORCEPROP 2 LAST CDS_LIB standard
J 0
(-2800 3800);
DISPLAY INVISIBLE (-2800 3800);
FORCEPROP 1 LAST OFFPAGE TRUE
J 0
(-2475 3675);
DISPLAY 0.872340 (-2475 3675);
PAINT GREEN (-2475 3675);
DISPLAY INVISIBLE (-2475 3675);
FORCEPROP 1 LAST COMMENT_BODY TRUE
J 0
(-2825 3700);
DISPLAY 0.872340 (-2825 3700);
PAINT GREEN (-2825 3700);
DISPLAY INVISIBLE (-2825 3700);
FORCEADD OFFPAGE..2
(-2800 3900);
FORCEPROP 2 LAST $XR0 172 
J 0
(-2611 3900);
DISPLAY 0.638298 (-2611 3900);
PAINT MONO (-2611 3900);
FORCEPROP 2 LAST PATH I239
J 0
(-2600 3950);
DISPLAY 1.021277 (-2600 3950);
DISPLAY INVISIBLE (-2600 3950);
FORCEPROP 2 LAST CDS_LIB standard
J 0
(-2800 3900);
DISPLAY INVISIBLE (-2800 3900);
FORCEPROP 1 LAST OFFPAGE TRUE
J 0
(-2475 3775);
DISPLAY 0.872340 (-2475 3775);
PAINT GREEN (-2475 3775);
DISPLAY INVISIBLE (-2475 3775);
FORCEPROP 1 LAST COMMENT_BODY TRUE
J 0
(-2845 3805);
DISPLAY 0.872340 (-2845 3805);
PAINT GREEN (-2845 3805);
DISPLAY INVISIBLE (-2845 3805);
FORCEADD OFFPAGE..2
(-2800 3600);
FORCEPROP 2 LAST $XR0 172 
J 0
(-2611 3600);
DISPLAY 0.638298 (-2611 3600);
PAINT MONO (-2611 3600);
FORCEPROP 2 LAST PATH I240
J 0
(-2600 3650);
DISPLAY 1.021277 (-2600 3650);
DISPLAY INVISIBLE (-2600 3650);
FORCEPROP 2 LAST CDS_LIB standard
J 0
(-2800 3600);
DISPLAY INVISIBLE (-2800 3600);
FORCEPROP 1 LAST OFFPAGE TRUE
J 0
(-2475 3475);
DISPLAY 0.872340 (-2475 3475);
PAINT GREEN (-2475 3475);
DISPLAY INVISIBLE (-2475 3475);
FORCEPROP 1 LAST COMMENT_BODY TRUE
J 0
(-2845 3505);
DISPLAY 0.872340 (-2845 3505);
PAINT GREEN (-2845 3505);
DISPLAY INVISIBLE (-2845 3505);
FORCEADD OFFPAGE..4
(-2800 3500);
FORCEPROP 2 LAST $XR0 172 
J 0
(-2614 3500);
DISPLAY 0.638298 (-2614 3500);
PAINT MONO (-2614 3500);
FORCEPROP 2 LAST PATH I241
J 0
(-2600 3550);
DISPLAY 1.021277 (-2600 3550);
DISPLAY INVISIBLE (-2600 3550);
FORCEPROP 2 LAST CDS_LIB standard
J 0
(-2800 3500);
DISPLAY INVISIBLE (-2800 3500);
FORCEPROP 1 LAST OFFPAGE TRUE
J 0
(-2475 3375);
DISPLAY 0.872340 (-2475 3375);
PAINT GREEN (-2475 3375);
DISPLAY INVISIBLE (-2475 3375);
FORCEPROP 1 LAST COMMENT_BODY TRUE
J 0
(-2825 3400);
DISPLAY 0.872340 (-2825 3400);
PAINT GREEN (-2825 3400);
DISPLAY INVISIBLE (-2825 3400);
FORCEADD UNIVERSAL_GND..1
(-2575 2475);
FORCEPROP 3 LASTPIN (-2575 2525) SIG_NAME GND\g
J 0
(-2565 2535);
DISPLAY 0.659574 (-2565 2535);
PAINT MONO (-2565 2535);
DISPLAY INVISIBLE (-2565 2535);
FORCEPROP 2 LAST CDS_LIB pure_quanta_power
J 0
(-2575 2475);
DISPLAY INVISIBLE (-2575 2475);
FORCEPROP 1 LAST PATH I242
J 0
(-2500 2475);
DISPLAY 0.872340 (-2500 2475);
PAINT AQUA (-2500 2475);
DISPLAY INVISIBLE (-2500 2475);
FORCEPROP 1 LAST HDL_POWER GND
J 1
(-2550 2400);
DISPLAY 0.872340 (-2550 2400);
PAINT GREEN (-2550 2400);
DISPLAY INVISIBLE (-2550 2400);
FORCEADD Q_RES..1
(-2925 2600);
FORCEPROP 1 LAST LOCATION PR441
J 0
(-2975 2650);
DISPLAY 0.489362 (-2975 2650);
PAINT SKYBLUE (-2975 2650);
FORCEPROP 0 LAST $SEC 1
J 0
(-2975 2675);
DISPLAY 0.680851 (-2975 2675);
PAINT MONO (-2975 2675);
DISPLAY INVISIBLE (-2975 2675);
FORCEPROP 0 LAST CDS_SEC 1
J 0
(-2975 2675);
DISPLAY 0.680851 (-2975 2675);
DISPLAY INVISIBLE (-2975 2675);
FORCEPROP 1 LASTPIN (-3025 2600) $PN 1
J 0
(-3013 2612);
DISPLAY 0.787234 (-3013 2612);
PAINT MONO (-3013 2612);
DISPLAY INVISIBLE (-3013 2612);
FORCEPROP 1 LASTPIN (-2825 2600) $PN 2
J 0
(-2863 2612);
DISPLAY 0.787234 (-2863 2612);
PAINT MONO (-2863 2612);
DISPLAY INVISIBLE (-2863 2612);
FORCEPROP 1 LAST PACK_TYPE 0402LF
J 0
(-2825 2550);
DISPLAY 0.489362 (-2825 2550);
PAINT SKYBLUE (-2825 2550);
FORCEPROP 1 LAST TOLERANCE 5%
J 0
(-2900 2550);
DISPLAY 0.489362 (-2900 2550);
PAINT SKYBLUE (-2900 2550);
FORCEPROP 1 LAST VALUE 0
J 2
(-2925 2550);
DISPLAY 0.489362 (-2925 2550);
PAINT SKYBLUE (-2925 2550);
FORCEPROP 1 LAST WATTAGE 1/16W
J 2
(-3000 2550);
DISPLAY 0.489362 (-3000 2550);
PAINT SKYBLUE (-3000 2550);
FORCEPROP 1 LAST MATERIAL CHIP
J 0
(-3250 2550);
DISPLAY 0.489362 (-3250 2550);
PAINT SKYBLUE (-3250 2550);
FORCEPROP 1 LAST PART_NUMBER CS00002JB38
J 0
(-3600 2550);
DISPLAY 0.489362 (-3600 2550);
PAINT SKYBLUE (-3600 2550);
FORCEPROP 2 LAST CDS_LIB pure_quanta
J 0
(-2925 2600);
DISPLAY INVISIBLE (-2925 2600);
FORCEPROP 1 LAST PATH I243
J 0
(-2975 2750);
DISPLAY 0.978723 (-2975 2750);
PAINT WHITE (-2975 2750);
DISPLAY INVISIBLE (-2975 2750);
FORCEADD Q_RES..2
(-5675 450);
FORCEPROP 1 LAST LOCATION PR599
J 0
(-5625 575);
DISPLAY 0.489362 (-5625 575);
PAINT SKYBLUE (-5625 575);
FORCEPROP 0 LAST $SEC 1
J 0
(-5625 600);
DISPLAY 0.680851 (-5625 600);
PAINT MONO (-5625 600);
DISPLAY INVISIBLE (-5625 600);
FORCEPROP 0 LAST CDS_SEC 1
J 0
(-5625 600);
DISPLAY 0.680851 (-5625 600);
DISPLAY INVISIBLE (-5625 600);
FORCEPROP 1 LASTPIN (-5675 550) $PN 1
J 0
(-5670 512);
DISPLAY 0.787234 (-5670 512);
PAINT MONO (-5670 512);
DISPLAY INVISIBLE (-5670 512);
FORCEPROP 1 LASTPIN (-5675 350) $PN 2
J 0
(-5670 360);
DISPLAY 0.787234 (-5670 360);
PAINT MONO (-5670 360);
DISPLAY INVISIBLE (-5670 360);
FORCEPROP 1 LAST WATTAGE 1/16W
J 0
(-5625 425);
DISPLAY 0.489362 (-5625 425);
PAINT SKYBLUE (-5625 425);
FORCEPROP 1 LAST MATERIAL EMPTY
J 0
(-5625 375);
DISPLAY 0.489362 (-5625 375);
PAINT RED (-5625 375);
FORCEPROP 1 LAST TOLERANCE 1%
J 0
(-5625 475);
DISPLAY 0.489362 (-5625 475);
PAINT SKYBLUE (-5625 475);
FORCEPROP 1 LAST VALUE 4.99K
J 0
(-5625 525);
DISPLAY 0.489362 (-5625 525);
PAINT SKYBLUE (-5625 525);
FORCEPROP 1 LAST PART_NUMBER CS24992FB07
J 0
(-5625 325);
DISPLAY 0.489362 (-5625 325);
PAINT SKYBLUE (-5625 325);
FORCEPROP 1 LAST PACK_TYPE 0402LF
J 0
(-5625 275);
DISPLAY 0.489362 (-5625 275);
PAINT SKYBLUE (-5625 275);
FORCEPROP 2 LAST CDS_LIB pure_quanta
J 0
(-5675 450);
DISPLAY INVISIBLE (-5675 450);
FORCEPROP 1 LAST PATH I244
J 0
(-5625 625);
DISPLAY 0.978723 (-5625 625);
PAINT WHITE (-5625 625);
DISPLAY INVISIBLE (-5625 625);
FORCEADD UNIVERSAL_GND..1
(-5675 250);
FORCEPROP 3 LASTPIN (-5675 300) SIG_NAME GND\g
J 0
(-5665 310);
DISPLAY 0.659574 (-5665 310);
PAINT MONO (-5665 310);
DISPLAY INVISIBLE (-5665 310);
FORCEPROP 2 LAST CDS_LIB pure_quanta_power
J 0
(-5675 250);
DISPLAY INVISIBLE (-5675 250);
FORCEPROP 1 LAST PATH I245
J 0
(-5600 250);
DISPLAY 0.872340 (-5600 250);
PAINT AQUA (-5600 250);
DISPLAY INVISIBLE (-5600 250);
FORCEPROP 1 LAST HDL_POWER GND
J 1
(-5650 175);
DISPLAY 0.872340 (-5650 175);
PAINT GREEN (-5650 175);
DISPLAY INVISIBLE (-5650 175);
FORCEADD Q_RES..2
(-7100 1375);
FORCEPROP 1 LAST LOCATION PR292
J 0
(-7050 1425);
DISPLAY 0.489362 (-7050 1425);
PAINT SKYBLUE (-7050 1425);
FORCEPROP 0 LAST $SEC 1
J 0
(-7050 1450);
DISPLAY 0.680851 (-7050 1450);
PAINT MONO (-7050 1450);
DISPLAY INVISIBLE (-7050 1450);
FORCEPROP 0 LAST CDS_SEC 1
J 0
(-7050 1450);
DISPLAY 1.021277 (-7050 1450);
DISPLAY INVISIBLE (-7050 1450);
FORCEPROP 1 LASTPIN (-7100 1475) $PN 1
J 0
(-7095 1437);
DISPLAY 0.489362 (-7095 1437);
PAINT MONO (-7095 1437);
FORCEPROP 1 LASTPIN (-7100 1275) $PN 2
J 0
(-7095 1285);
DISPLAY 0.489362 (-7095 1285);
PAINT MONO (-7095 1285);
FORCEPROP 1 LAST WATTAGE 1/16W
J 0
(-7050 1350);
DISPLAY 0.489362 (-7050 1350);
PAINT SKYBLUE (-7050 1350);
FORCEPROP 1 LAST MATERIAL CHIP
J 0
(-7050 1325);
DISPLAY 0.489362 (-7050 1325);
PAINT SKYBLUE (-7050 1325);
FORCEPROP 1 LAST TOLERANCE 1%
J 0
(-7050 1375);
DISPLAY 0.489362 (-7050 1375);
PAINT SKYBLUE (-7050 1375);
FORCEPROP 1 LAST VALUE 681
J 0
(-7050 1400);
DISPLAY 0.489362 (-7050 1400);
PAINT SKYBLUE (-7050 1400);
FORCEPROP 1 LAST PART_NUMBER CS16812FB02
J 0
(-7050 1300);
DISPLAY 0.489362 (-7050 1300);
PAINT SKYBLUE (-7050 1300);
FORCEPROP 1 LAST PACK_TYPE 0402LF
J 0
(-7050 1275);
DISPLAY 0.489362 (-7050 1275);
PAINT SKYBLUE (-7050 1275);
FORCEPROP 2 LAST CDS_LIB pure_quanta
J 0
(-7100 1375);
DISPLAY INVISIBLE (-7100 1375);
FORCEPROP 1 LAST PATH I3
J 0
(-7050 1550);
DISPLAY 0.978723 (-7050 1550);
PAINT WHITE (-7050 1550);
DISPLAY INVISIBLE (-7050 1550);
FORCEADD Q_CAP..1
(-2750 1025);
FORCEPROP 1 LAST LOCATION PC472
J 0
(-2700 1125);
DISPLAY 0.489362 (-2700 1125);
PAINT SKYBLUE (-2700 1125);
FORCEPROP 0 LAST $SEC 1
J 0
(-2700 1150);
DISPLAY 0.680851 (-2700 1150);
PAINT MONO (-2700 1150);
DISPLAY INVISIBLE (-2700 1150);
FORCEPROP 0 LAST CDS_SEC 1
J 0
(-2700 1150);
DISPLAY 1.021277 (-2700 1150);
DISPLAY INVISIBLE (-2700 1150);
FORCEPROP 1 LASTPIN (-2750 1125) $PN 1
J 0
(-2740 1105);
DISPLAY 0.489362 (-2740 1105);
PAINT MONO (-2740 1105);
FORCEPROP 1 LASTPIN (-2750 925) $PN 2
J 0
(-2740 905);
DISPLAY 0.489362 (-2740 905);
PAINT MONO (-2740 905);
FORCEPROP 1 LAST MATERIAL X7R
J 0
(-2700 925);
DISPLAY 0.489362 (-2700 925);
PAINT SKYBLUE (-2700 925);
FORCEPROP 1 LAST TOLERANCE 10%
J 0
(-2700 975);
DISPLAY 0.489362 (-2700 975);
PAINT SKYBLUE (-2700 975);
FORCEPROP 1 LAST VALUE 470PF
J 0
(-2700 1075);
DISPLAY 0.489362 (-2700 1075);
PAINT SKYBLUE (-2700 1075);
FORCEPROP 1 LAST PART_NUMBER TMP_QCH14706KB18
J 0
(-2700 875);
DISPLAY 0.489362 (-2700 875);
PAINT SKYBLUE (-2700 875);
FORCEPROP 1 LAST VOLTAGE 50V
J 0
(-2700 1025);
DISPLAY 0.489362 (-2700 1025);
PAINT SKYBLUE (-2700 1025);
FORCEPROP 1 LAST PACK_TYPE 0402
J 0
(-2700 825);
DISPLAY 0.489362 (-2700 825);
PAINT SKYBLUE (-2700 825);
FORCEPROP 2 LAST CDS_LIB pure_quanta
J 0
(-2750 1025);
DISPLAY INVISIBLE (-2750 1025);
FORCEPROP 1 LAST PATH I35
J 0
(-2700 1175);
DISPLAY 0.978723 (-2700 1175);
PAINT WHITE (-2700 1175);
DISPLAY INVISIBLE (-2700 1175);
FORCEADD Q_CAP..1
(-3375 700);
FORCEPROP 1 LAST LOCATION PC469
J 0
(-3325 800);
DISPLAY 0.489362 (-3325 800);
PAINT SKYBLUE (-3325 800);
FORCEPROP 0 LAST $SEC 1
J 0
(-3325 825);
DISPLAY 0.680851 (-3325 825);
PAINT MONO (-3325 825);
DISPLAY INVISIBLE (-3325 825);
FORCEPROP 0 LAST CDS_SEC 1
J 0
(-3325 825);
DISPLAY 1.021277 (-3325 825);
DISPLAY INVISIBLE (-3325 825);
FORCEPROP 1 LASTPIN (-3375 800) $PN 1
J 0
(-3365 780);
DISPLAY 0.489362 (-3365 780);
PAINT MONO (-3365 780);
FORCEPROP 1 LASTPIN (-3375 600) $PN 2
J 0
(-3365 580);
DISPLAY 0.489362 (-3365 580);
PAINT MONO (-3365 580);
FORCEPROP 1 LAST MATERIAL X7R
J 0
(-3325 600);
DISPLAY 0.489362 (-3325 600);
PAINT SKYBLUE (-3325 600);
FORCEPROP 1 LAST TOLERANCE 10%
J 0
(-3325 650);
DISPLAY 0.489362 (-3325 650);
PAINT SKYBLUE (-3325 650);
FORCEPROP 1 LAST VALUE 470PF
J 0
(-3325 750);
DISPLAY 0.489362 (-3325 750);
PAINT SKYBLUE (-3325 750);
FORCEPROP 1 LAST PART_NUMBER TMP_QCH14706KB18
J 0
(-3325 550);
DISPLAY 0.489362 (-3325 550);
PAINT SKYBLUE (-3325 550);
FORCEPROP 1 LAST VOLTAGE 50V
J 0
(-3325 700);
DISPLAY 0.489362 (-3325 700);
PAINT SKYBLUE (-3325 700);
FORCEPROP 1 LAST PACK_TYPE 0402
J 0
(-3325 500);
DISPLAY 0.489362 (-3325 500);
PAINT SKYBLUE (-3325 500);
FORCEPROP 2 LAST CDS_LIB pure_quanta
J 0
(-3375 700);
DISPLAY INVISIBLE (-3375 700);
FORCEPROP 1 LAST PATH I36
J 0
(-3325 850);
DISPLAY 0.978723 (-3325 850);
PAINT WHITE (-3325 850);
DISPLAY INVISIBLE (-3325 850);
FORCEADD UNIVERSAL_GND..1
(-3375 425);
FORCEPROP 3 LASTPIN (-3375 475) SIG_NAME GND\g
J 0
(-3365 485);
DISPLAY 0.659574 (-3365 485);
PAINT MONO (-3365 485);
DISPLAY INVISIBLE (-3365 485);
FORCEPROP 2 LAST CDS_LIB pure_quanta_power
J 0
(-3375 425);
DISPLAY INVISIBLE (-3375 425);
FORCEPROP 1 LAST PATH I37
J 0
(-3300 425);
DISPLAY 0.872340 (-3300 425);
PAINT AQUA (-3300 425);
DISPLAY INVISIBLE (-3300 425);
FORCEPROP 1 LAST HDL_POWER GND
J 1
(-3350 350);
DISPLAY 0.872340 (-3350 350);
PAINT GREEN (-3350 350);
DISPLAY INVISIBLE (-3350 350);
FORCEADD UNIVERSAL_GND..1
(-2750 775);
FORCEPROP 3 LASTPIN (-2750 825) SIG_NAME GND\g
J 0
(-2740 835);
DISPLAY 0.659574 (-2740 835);
PAINT MONO (-2740 835);
DISPLAY INVISIBLE (-2740 835);
FORCEPROP 2 LAST CDS_LIB pure_quanta_power
J 0
(-2750 775);
DISPLAY INVISIBLE (-2750 775);
FORCEPROP 1 LAST PATH I38
J 0
(-2675 775);
DISPLAY 0.872340 (-2675 775);
PAINT AQUA (-2675 775);
DISPLAY INVISIBLE (-2675 775);
FORCEPROP 1 LAST HDL_POWER GND
J 1
(-2725 700);
DISPLAY 0.872340 (-2725 700);
PAINT GREEN (-2725 700);
DISPLAY INVISIBLE (-2725 700);
FORCEADD Q_RES..2
(-7775 2025);
FORCEPROP 1 LAST LOCATION PR285
J 0
(-7725 2075);
DISPLAY 0.489362 (-7725 2075);
PAINT SKYBLUE (-7725 2075);
FORCEPROP 0 LAST $SEC 1
J 0
(-7750 2100);
DISPLAY 0.680851 (-7750 2100);
PAINT MONO (-7750 2100);
DISPLAY INVISIBLE (-7750 2100);
FORCEPROP 0 LAST CDS_SEC 1
J 0
(-7750 2100);
DISPLAY 1.021277 (-7750 2100);
DISPLAY INVISIBLE (-7750 2100);
FORCEPROP 1 LASTPIN (-7775 2125) $PN 1
J 0
(-7770 2087);
DISPLAY 0.489362 (-7770 2087);
PAINT MONO (-7770 2087);
FORCEPROP 1 LASTPIN (-7775 1925) $PN 2
J 0
(-7770 1935);
DISPLAY 0.489362 (-7770 1935);
PAINT MONO (-7770 1935);
FORCEPROP 1 LAST WATTAGE 1/16W
J 0
(-7725 2000);
DISPLAY 0.489362 (-7725 2000);
PAINT SKYBLUE (-7725 2000);
FORCEPROP 1 LAST MATERIAL CHIP
J 0
(-7725 1975);
DISPLAY 0.489362 (-7725 1975);
PAINT SKYBLUE (-7725 1975);
FORCEPROP 1 LAST TOLERANCE 1%
J 0
(-7725 2025);
DISPLAY 0.489362 (-7725 2025);
PAINT SKYBLUE (-7725 2025);
FORCEPROP 1 LAST VALUE 1K
J 0
(-7725 2050);
DISPLAY 0.489362 (-7725 2050);
PAINT SKYBLUE (-7725 2050);
FORCEPROP 1 LAST PART_NUMBER TMP_QCS21002FB24
J 0
(-7725 1950);
DISPLAY 0.489362 (-7725 1950);
PAINT SKYBLUE (-7725 1950);
FORCEPROP 1 LAST PACK_TYPE 0402LF
J 0
(-7725 1925);
DISPLAY 0.489362 (-7725 1925);
PAINT SKYBLUE (-7725 1925);
FORCEPROP 2 LAST CDS_LIB pure_quanta
J 0
(-7775 2025);
DISPLAY INVISIBLE (-7775 2025);
FORCEPROP 1 LAST PATH I4
J 0
(-7725 2200);
DISPLAY 0.978723 (-7725 2200);
PAINT WHITE (-7725 2200);
DISPLAY INVISIBLE (-7725 2200);
FORCEADD Q_RES..1
(-6125 6375);
FORCEPROP 1 LAST LOCATION PR300
J 0
(-6175 6425);
DISPLAY 0.489362 (-6175 6425);
PAINT SKYBLUE (-6175 6425);
FORCEPROP 0 LAST $SEC 1
J 0
(-6175 6450);
DISPLAY 0.680851 (-6175 6450);
PAINT MONO (-6175 6450);
DISPLAY INVISIBLE (-6175 6450);
FORCEPROP 0 LAST CDS_SEC 1
J 0
(-6175 6450);
DISPLAY 1.021277 (-6175 6450);
DISPLAY INVISIBLE (-6175 6450);
FORCEPROP 1 LASTPIN (-6225 6375) $PN 1
J 0
(-6213 6387);
DISPLAY 0.489362 (-6213 6387);
PAINT MONO (-6213 6387);
FORCEPROP 1 LASTPIN (-6025 6375) $PN 2
J 0
(-6063 6387);
DISPLAY 0.489362 (-6063 6387);
PAINT MONO (-6063 6387);
FORCEPROP 1 LAST PACK_TYPE 0402LF
J 0
(-6025 6275);
DISPLAY 0.489362 (-6025 6275);
PAINT SKYBLUE (-6025 6275);
FORCEPROP 1 LAST VALUE 1K
J 2
(-6275 6400);
DISPLAY 0.489362 (-6275 6400);
PAINT SKYBLUE (-6275 6400);
FORCEPROP 1 LAST WATTAGE 1/16W
J 0
(-6025 6325);
DISPLAY 0.489362 (-6025 6325);
PAINT SKYBLUE (-6025 6325);
FORCEPROP 1 LAST PART_NUMBER TMP_QCS21002FB24
J 0
(-6450 6325);
DISPLAY 0.489362 (-6450 6325);
PAINT SKYBLUE (-6450 6325);
FORCEPROP 1 LAST MATERIAL CHIP
J 0
(-6450 6275);
DISPLAY 0.489362 (-6450 6275);
PAINT SKYBLUE (-6450 6275);
FORCEPROP 1 LAST TOLERANCE 1%
J 0
(-6000 6400);
DISPLAY 0.489362 (-6000 6400);
PAINT SKYBLUE (-6000 6400);
FORCEPROP 2 LAST CDS_LIB pure_quanta
J 0
(-6125 6375);
DISPLAY INVISIBLE (-6125 6375);
FORCEPROP 1 LAST PATH I41
J 0
(-6175 6525);
DISPLAY 0.978723 (-6175 6525);
PAINT WHITE (-6175 6525);
DISPLAY INVISIBLE (-6175 6525);
FORCEADD Q_CAP..2
(-5250 6375);
FORCEPROP 1 LAST LOCATION PC467
J 1
(-5250 6450);
DISPLAY 0.489362 (-5250 6450);
PAINT SKYBLUE (-5250 6450);
FORCEPROP 0 LAST $SEC 1
J 0
(-5250 6475);
DISPLAY 0.680851 (-5250 6475);
PAINT MONO (-5250 6475);
DISPLAY INVISIBLE (-5250 6475);
FORCEPROP 0 LAST CDS_SEC 1
J 0
(-5250 6475);
DISPLAY 1.021277 (-5250 6475);
DISPLAY INVISIBLE (-5250 6475);
FORCEPROP 1 LASTPIN (-5350 6375) $PN 1
J 0
(-5360 6390);
DISPLAY 0.489362 (-5360 6390);
PAINT MONO (-5360 6390);
FORCEPROP 1 LASTPIN (-5150 6375) $PN 2
J 0
(-5165 6390);
DISPLAY 0.489362 (-5165 6390);
PAINT MONO (-5165 6390);
FORCEPROP 1 LAST MATERIAL EMPTY
J 0
(-5525 6250);
DISPLAY 0.489362 (-5525 6250);
PAINT RED (-5525 6250);
FORCEPROP 1 LAST VALUE 1000PF
J 2
(-5375 6425);
DISPLAY 0.489362 (-5375 6425);
PAINT SKYBLUE (-5375 6425);
FORCEPROP 1 LAST VOLTAGE 50V
J 0
(-5150 6425);
DISPLAY 0.489362 (-5150 6425);
PAINT SKYBLUE (-5150 6425);
FORCEPROP 1 LAST TOLERANCE 5%
J 0
(-5125 6250);
DISPLAY 0.489362 (-5125 6250);
PAINT SKYBLUE (-5125 6250);
FORCEPROP 1 LAST PART_NUMBER TMP_QCH21006JB10
J 1
(-5400 6300);
DISPLAY 0.489362 (-5400 6300);
PAINT SKYBLUE (-5400 6300);
FORCEPROP 1 LAST PACK_TYPE 0402
J 0
(-5125 6300);
DISPLAY 0.489362 (-5125 6300);
PAINT SKYBLUE (-5125 6300);
FORCEPROP 2 LAST CDS_LIB pure_quanta
J 0
(-5250 6375);
DISPLAY INVISIBLE (-5250 6375);
FORCEPROP 1 LAST PATH I42
J 0
(-5250 6575);
DISPLAY 0.978723 (-5250 6575);
PAINT WHITE (-5250 6575);
DISPLAY INVISIBLE (-5250 6575);
FORCEADD Q_RES..1
(-5900 6100);
FORCEPROP 1 LAST LOCATION PR311
J 0
(-5950 6150);
DISPLAY 0.489362 (-5950 6150);
PAINT SKYBLUE (-5950 6150);
FORCEPROP 0 LAST $SEC 1
J 0
(-5775 6150);
DISPLAY 0.680851 (-5775 6150);
PAINT MONO (-5775 6150);
DISPLAY INVISIBLE (-5775 6150);
FORCEPROP 0 LAST CDS_SEC 1
J 0
(-5775 6150);
DISPLAY 1.021277 (-5775 6150);
DISPLAY INVISIBLE (-5775 6150);
FORCEPROP 1 LASTPIN (-6000 6100) $PN 1
J 0
(-5988 6112);
DISPLAY 0.489362 (-5988 6112);
PAINT MONO (-5988 6112);
FORCEPROP 1 LASTPIN (-5800 6100) $PN 2
J 0
(-5838 6112);
DISPLAY 0.489362 (-5838 6112);
PAINT MONO (-5838 6112);
FORCEPROP 1 LAST WATTAGE 1/16W
J 0
(-5800 6050);
DISPLAY 0.489362 (-5800 6050);
PAINT SKYBLUE (-5800 6050);
FORCEPROP 1 LAST TOLERANCE 5%
J 0
(-5775 6125);
DISPLAY 0.489362 (-5775 6125);
PAINT SKYBLUE (-5775 6125);
FORCEPROP 1 LAST PART_NUMBER CS00002JB38
J 0
(-6150 6050);
DISPLAY 0.489362 (-6150 6050);
PAINT SKYBLUE (-6150 6050);
FORCEPROP 1 LAST PACK_TYPE 0402LF
J 0
(-5800 6025);
DISPLAY 0.489362 (-5800 6025);
PAINT SKYBLUE (-5800 6025);
FORCEPROP 1 LAST VALUE 0
J 2
(-6025 6125);
DISPLAY 0.489362 (-6025 6125);
PAINT SKYBLUE (-6025 6125);
FORCEPROP 1 LAST MATERIAL CHIP
J 0
(-6150 6025);
DISPLAY 0.489362 (-6150 6025);
PAINT SKYBLUE (-6150 6025);
FORCEPROP 2 LAST CDS_LIB pure_quanta
J 0
(-5900 6100);
DISPLAY INVISIBLE (-5900 6100);
FORCEPROP 1 LAST PATH I43
J 0
(-5950 6250);
DISPLAY 0.978723 (-5950 6250);
PAINT WHITE (-5950 6250);
DISPLAY INVISIBLE (-5950 6250);
FORCEADD UNIVERSAL_GND..1
(-5000 6300);
FORCEPROP 3 LASTPIN (-5000 6350) SIG_NAME GND\g
J 0
(-4990 6360);
DISPLAY 0.659574 (-4990 6360);
PAINT MONO (-4990 6360);
DISPLAY INVISIBLE (-4990 6360);
FORCEPROP 2 LAST CDS_LIB pure_quanta_power
J 0
(-5000 6300);
DISPLAY INVISIBLE (-5000 6300);
FORCEPROP 1 LAST PATH I44
J 0
(-4925 6300);
DISPLAY 0.872340 (-4925 6300);
PAINT AQUA (-4925 6300);
DISPLAY INVISIBLE (-4925 6300);
FORCEPROP 1 LAST HDL_POWER GND
J 1
(-4975 6225);
DISPLAY 0.872340 (-4975 6225);
PAINT GREEN (-4975 6225);
DISPLAY INVISIBLE (-4975 6225);
FORCEADD OFFPAGE..2
R 2
(-6625 6100);
FORCEPROP 2 LAST $XR0 81 
J 0
(-6879 6100);
DISPLAY 0.638298 (-6879 6100);
PAINT MONO (-6879 6100);
FORCEPROP 2 LAST CDS_LIB standard
J 2
(-6625 6100);
DISPLAY INVISIBLE (-6625 6100);
FORCEPROP 1 LAST OFFPAGE TRUE
J 2
(-6950 5975);
DISPLAY 0.872340 (-6950 5975);
PAINT GREEN (-6950 5975);
DISPLAY INVISIBLE (-6950 5975);
FORCEPROP 1 LAST COMMENT_BODY TRUE
J 2
(-6580 6005);
DISPLAY 0.872340 (-6580 6005);
PAINT GREEN (-6580 6005);
DISPLAY INVISIBLE (-6580 6005);
FORCEPROP 2 LAST PATH I45
J 2
(-6800 6175);
DISPLAY 1.021277 (-6800 6175);
DISPLAY INVISIBLE (-6800 6175);
FORCEADD VCC_CORE..1
(-6525 6500);
FORCEPROP 3 LASTPIN (-6525 6450) SIG_NAME P3V3_STBY\g
J 0
(-6515 6460);
DISPLAY 0.659574 (-6515 6460);
PAINT MONO (-6515 6460);
DISPLAY INVISIBLE (-6515 6460);
FORCEPROP 1 LAST HDL_POWER P3V3_STBY
J 1
(-6525 6550);
DISPLAY 0.489362 (-6525 6550);
PAINT GREEN (-6525 6550);
FORCEPROP 2 LAST CDS_LIB pure_quanta_power
J 0
(-6525 6500);
DISPLAY INVISIBLE (-6525 6500);
FORCEPROP 1 LAST PATH I46
J 0
(-6475 6525);
DISPLAY 0.872340 (-6475 6525);
PAINT AQUA (-6475 6525);
DISPLAY INVISIBLE (-6475 6525);
FORCEADD Q_RES..1
(-5900 5950);
FORCEPROP 1 LAST LOCATION PR312
J 0
(-5950 5975);
DISPLAY 0.489362 (-5950 5975);
PAINT SKYBLUE (-5950 5975);
FORCEPROP 0 LAST $SEC 1
J 0
(-5775 6000);
DISPLAY 0.680851 (-5775 6000);
PAINT MONO (-5775 6000);
DISPLAY INVISIBLE (-5775 6000);
FORCEPROP 0 LAST CDS_SEC 1
J 0
(-5775 6000);
DISPLAY 1.021277 (-5775 6000);
DISPLAY INVISIBLE (-5775 6000);
FORCEPROP 1 LASTPIN (-6000 5950) $PN 1
J 0
(-5988 5962);
DISPLAY 0.489362 (-5988 5962);
PAINT MONO (-5988 5962);
FORCEPROP 1 LASTPIN (-5800 5950) $PN 2
J 0
(-5838 5962);
DISPLAY 0.489362 (-5838 5962);
PAINT MONO (-5838 5962);
FORCEPROP 1 LAST WATTAGE 1/16W
J 0
(-5800 5900);
DISPLAY 0.489362 (-5800 5900);
PAINT SKYBLUE (-5800 5900);
FORCEPROP 1 LAST MATERIAL CHIP
J 0
(-6150 5875);
DISPLAY 0.489362 (-6150 5875);
PAINT SKYBLUE (-6150 5875);
FORCEPROP 1 LAST TOLERANCE 5%
J 0
(-5775 5975);
DISPLAY 0.489362 (-5775 5975);
PAINT SKYBLUE (-5775 5975);
FORCEPROP 1 LAST VALUE 0
J 2
(-6025 5975);
DISPLAY 0.489362 (-6025 5975);
PAINT SKYBLUE (-6025 5975);
FORCEPROP 1 LAST PACK_TYPE 0402LF
J 0
(-5800 5875);
DISPLAY 0.489362 (-5800 5875);
PAINT SKYBLUE (-5800 5875);
FORCEPROP 1 LAST PART_NUMBER CS00002JB38
J 0
(-6150 5900);
DISPLAY 0.489362 (-6150 5900);
PAINT SKYBLUE (-6150 5900);
FORCEPROP 2 LAST CDS_LIB pure_quanta
J 0
(-5900 5950);
DISPLAY INVISIBLE (-5900 5950);
FORCEPROP 1 LAST PATH I47
J 0
(-5950 6100);
DISPLAY 0.978723 (-5950 6100);
PAINT WHITE (-5950 6100);
DISPLAY INVISIBLE (-5950 6100);
FORCEADD Q_CAP..2
(-5225 5825);
FORCEPROP 1 LAST LOCATION PC468
J 1
(-5225 5875);
DISPLAY 0.489362 (-5225 5875);
PAINT SKYBLUE (-5225 5875);
FORCEPROP 0 LAST $SEC 1
J 0
(-5225 5925);
DISPLAY 0.680851 (-5225 5925);
PAINT MONO (-5225 5925);
DISPLAY INVISIBLE (-5225 5925);
FORCEPROP 0 LAST CDS_SEC 1
J 0
(-5225 5925);
DISPLAY 1.021277 (-5225 5925);
DISPLAY INVISIBLE (-5225 5925);
FORCEPROP 1 LASTPIN (-5325 5825) $PN 1
J 0
(-5335 5840);
DISPLAY 0.489362 (-5335 5840);
PAINT MONO (-5335 5840);
FORCEPROP 1 LASTPIN (-5125 5825) $PN 2
J 0
(-5140 5840);
DISPLAY 0.489362 (-5140 5840);
PAINT MONO (-5140 5840);
FORCEPROP 1 LAST VALUE 1000PF
J 2
(-5400 5850);
DISPLAY 0.489362 (-5400 5850);
PAINT SKYBLUE (-5400 5850);
FORCEPROP 1 LAST PACK_TYPE 0402
J 0
(-5125 5800);
DISPLAY 0.489362 (-5125 5800);
PAINT SKYBLUE (-5125 5800);
FORCEPROP 1 LAST VOLTAGE 50V
J 0
(-5075 5850);
DISPLAY 0.489362 (-5075 5850);
PAINT SKYBLUE (-5075 5850);
FORCEPROP 1 LAST MATERIAL X7R
J 0
(-5650 5775);
DISPLAY 0.489362 (-5650 5775);
PAINT SKYBLUE (-5650 5775);
FORCEPROP 1 LAST TOLERANCE 5%
J 0
(-5125 5775);
DISPLAY 0.489362 (-5125 5775);
PAINT SKYBLUE (-5125 5775);
FORCEPROP 1 LAST PART_NUMBER TMP_QCH21006JB10
J 0
(-5650 5800);
DISPLAY 0.489362 (-5650 5800);
PAINT SKYBLUE (-5650 5800);
FORCEPROP 2 LAST CDS_LIB pure_quanta
J 0
(-5225 5825);
DISPLAY INVISIBLE (-5225 5825);
FORCEPROP 1 LAST PATH I49
J 0
(-5225 6025);
DISPLAY 0.978723 (-5225 6025);
PAINT WHITE (-5225 6025);
DISPLAY INVISIBLE (-5225 6025);
FORCEADD UNIVERSAL_GND..1
(-7100 1175);
FORCEPROP 3 LASTPIN (-7100 1225) SIG_NAME GND\g
J 0
(-7090 1235);
DISPLAY 0.659574 (-7090 1235);
PAINT MONO (-7090 1235);
DISPLAY INVISIBLE (-7090 1235);
FORCEPROP 2 LAST CDS_LIB pure_quanta_power
J 0
(-7100 1175);
DISPLAY INVISIBLE (-7100 1175);
FORCEPROP 1 LAST PATH I5
J 0
(-7025 1175);
DISPLAY 0.872340 (-7025 1175);
PAINT AQUA (-7025 1175);
DISPLAY INVISIBLE (-7025 1175);
FORCEPROP 1 LAST HDL_POWER GND
J 1
(-7075 1100);
DISPLAY 0.872340 (-7075 1100);
PAINT GREEN (-7075 1100);
DISPLAY INVISIBLE (-7075 1100);
FORCEADD UNIVERSAL_GND..1
(-5000 5750);
FORCEPROP 3 LASTPIN (-5000 5800) SIG_NAME GND\g
J 0
(-4990 5810);
DISPLAY 0.659574 (-4990 5810);
PAINT MONO (-4990 5810);
DISPLAY INVISIBLE (-4990 5810);
FORCEPROP 2 LAST CDS_LIB pure_quanta_power
J 0
(-5000 5750);
DISPLAY INVISIBLE (-5000 5750);
FORCEPROP 1 LAST PATH I50
J 0
(-4925 5750);
DISPLAY 0.872340 (-4925 5750);
PAINT AQUA (-4925 5750);
DISPLAY INVISIBLE (-4925 5750);
FORCEPROP 1 LAST HDL_POWER GND
J 1
(-4975 5675);
DISPLAY 0.872340 (-4975 5675);
PAINT GREEN (-4975 5675);
DISPLAY INVISIBLE (-4975 5675);
FORCEADD Q_RES..2
(-7975 5975);
FORCEPROP 1 LAST LOCATION PR287
J 0
(-7925 6100);
DISPLAY 0.489362 (-7925 6100);
PAINT SKYBLUE (-7925 6100);
FORCEPROP 0 LAST $SEC 1
J 0
(-7925 6125);
DISPLAY 0.680851 (-7925 6125);
PAINT MONO (-7925 6125);
DISPLAY INVISIBLE (-7925 6125);
FORCEPROP 0 LAST CDS_SEC 1
J 0
(-7925 6125);
DISPLAY 1.021277 (-7925 6125);
DISPLAY INVISIBLE (-7925 6125);
FORCEPROP 1 LASTPIN (-7975 6075) $PN 1
J 0
(-7970 6037);
DISPLAY 0.489362 (-7970 6037);
PAINT MONO (-7970 6037);
FORCEPROP 1 LASTPIN (-7975 5875) $PN 2
J 0
(-7970 5885);
DISPLAY 0.489362 (-7970 5885);
PAINT MONO (-7970 5885);
FORCEPROP 1 LAST WATTAGE 1/16W
J 0
(-7925 5950);
DISPLAY 0.489362 (-7925 5950);
PAINT SKYBLUE (-7925 5950);
FORCEPROP 1 LAST MATERIAL EMPTY
J 0
(-7925 5900);
DISPLAY 0.489362 (-7925 5900);
PAINT RED (-7925 5900);
FORCEPROP 1 LAST TOLERANCE 1%
J 0
(-7925 6000);
DISPLAY 0.489362 (-7925 6000);
PAINT SKYBLUE (-7925 6000);
FORCEPROP 1 LAST PACK_TYPE 0402LF
J 0
(-7925 5850);
DISPLAY 0.489362 (-7925 5850);
PAINT SKYBLUE (-7925 5850);
FORCEPROP 1 LAST VALUE 1K
J 0
(-7925 6050);
DISPLAY 0.489362 (-7925 6050);
PAINT SKYBLUE (-7925 6050);
FORCEPROP 2 LAST CDS_LIB pure_quanta
J 0
(-7975 5975);
DISPLAY INVISIBLE (-7975 5975);
FORCEPROP 1 LAST PATH I55
J 0
(-7925 6150);
DISPLAY 0.978723 (-7925 6150);
PAINT WHITE (-7925 6150);
DISPLAY INVISIBLE (-7925 6150);
FORCEPROP 1 LAST PART_NUMBER TMP_QCS21002FB24
J 0
(-7935 5850);
DISPLAY 0.489362 (-7935 5850);
PAINT SKYBLUE (-7935 5850);
DISPLAY INVISIBLE (-7935 5850);
FORCEADD Q_RES..2
(-8325 5975);
FORCEPROP 1 LAST LOCATION PR284
J 0
(-8275 6100);
DISPLAY 0.489362 (-8275 6100);
PAINT SKYBLUE (-8275 6100);
FORCEPROP 0 LAST $SEC 1
J 0
(-8275 6125);
DISPLAY 0.680851 (-8275 6125);
PAINT MONO (-8275 6125);
DISPLAY INVISIBLE (-8275 6125);
FORCEPROP 0 LAST CDS_SEC 1
J 0
(-8275 6125);
DISPLAY 1.021277 (-8275 6125);
DISPLAY INVISIBLE (-8275 6125);
FORCEPROP 1 LASTPIN (-8325 6075) $PN 1
J 0
(-8320 6037);
DISPLAY 0.489362 (-8320 6037);
PAINT MONO (-8320 6037);
FORCEPROP 1 LASTPIN (-8325 5875) $PN 2
J 0
(-8320 5885);
DISPLAY 0.489362 (-8320 5885);
PAINT MONO (-8320 5885);
FORCEPROP 1 LAST WATTAGE 1/16W
J 0
(-8275 5950);
DISPLAY 0.489362 (-8275 5950);
PAINT SKYBLUE (-8275 5950);
FORCEPROP 1 LAST MATERIAL EMPTY
J 0
(-8275 5900);
DISPLAY 0.489362 (-8275 5900);
PAINT RED (-8275 5900);
FORCEPROP 1 LAST TOLERANCE 1%
J 0
(-8275 6000);
DISPLAY 0.489362 (-8275 6000);
PAINT SKYBLUE (-8275 6000);
FORCEPROP 1 LAST VALUE 1K
J 0
(-8275 6050);
DISPLAY 0.489362 (-8275 6050);
PAINT SKYBLUE (-8275 6050);
FORCEPROP 1 LAST PACK_TYPE 0402LF
J 0
(-8275 5850);
DISPLAY 0.489362 (-8275 5850);
PAINT SKYBLUE (-8275 5850);
FORCEPROP 2 LAST CDS_LIB pure_quanta
J 0
(-8325 5975);
DISPLAY INVISIBLE (-8325 5975);
FORCEPROP 1 LAST PATH I56
J 0
(-8275 6150);
DISPLAY 0.978723 (-8275 6150);
PAINT WHITE (-8275 6150);
DISPLAY INVISIBLE (-8275 6150);
FORCEPROP 1 LAST PART_NUMBER TMP_QCS21002FB24
J 0
(-8275 5850);
DISPLAY 0.489362 (-8275 5850);
PAINT SKYBLUE (-8275 5850);
DISPLAY INVISIBLE (-8275 5850);
FORCEADD Q_RES..2
(-7675 5975);
FORCEPROP 1 LAST LOCATION PR289
J 0
(-7625 6100);
DISPLAY 0.489362 (-7625 6100);
PAINT SKYBLUE (-7625 6100);
FORCEPROP 0 LAST $SEC 1
J 0
(-7625 6125);
DISPLAY 0.680851 (-7625 6125);
PAINT MONO (-7625 6125);
DISPLAY INVISIBLE (-7625 6125);
FORCEPROP 0 LAST CDS_SEC 1
J 0
(-7625 6125);
DISPLAY 1.021277 (-7625 6125);
DISPLAY INVISIBLE (-7625 6125);
FORCEPROP 1 LASTPIN (-7675 6075) $PN 1
J 0
(-7670 6037);
DISPLAY 0.489362 (-7670 6037);
PAINT MONO (-7670 6037);
FORCEPROP 1 LASTPIN (-7675 5875) $PN 2
J 0
(-7670 5885);
DISPLAY 0.489362 (-7670 5885);
PAINT MONO (-7670 5885);
FORCEPROP 1 LAST WATTAGE 1/16W
J 0
(-7625 5950);
DISPLAY 0.489362 (-7625 5950);
PAINT SKYBLUE (-7625 5950);
FORCEPROP 1 LAST MATERIAL EMPTY
J 0
(-7625 5900);
DISPLAY 0.489362 (-7625 5900);
PAINT RED (-7625 5900);
FORCEPROP 1 LAST VALUE 1K
J 0
(-7625 6050);
DISPLAY 0.489362 (-7625 6050);
PAINT SKYBLUE (-7625 6050);
FORCEPROP 1 LAST PACK_TYPE 0402LF
J 0
(-7625 5850);
DISPLAY 0.489362 (-7625 5850);
PAINT SKYBLUE (-7625 5850);
FORCEPROP 1 LAST TOLERANCE 1%
J 0
(-7625 6000);
DISPLAY 0.489362 (-7625 6000);
PAINT SKYBLUE (-7625 6000);
FORCEPROP 2 LAST CDS_LIB pure_quanta
J 0
(-7675 5975);
DISPLAY INVISIBLE (-7675 5975);
FORCEPROP 1 LAST PATH I57
J 0
(-7625 6150);
DISPLAY 0.978723 (-7625 6150);
PAINT WHITE (-7625 6150);
DISPLAY INVISIBLE (-7625 6150);
FORCEPROP 1 LAST PART_NUMBER TMP_QCS21002FB24
J 0
(-7635 5850);
DISPLAY 0.489362 (-7635 5850);
PAINT SKYBLUE (-7635 5850);
DISPLAY INVISIBLE (-7635 5850);
FORCEADD Q_RES..2
(-7400 5975);
FORCEPROP 1 LAST LOCATION PR293
J 0
(-7350 6100);
DISPLAY 0.489362 (-7350 6100);
PAINT SKYBLUE (-7350 6100);
FORCEPROP 0 LAST $SEC 1
J 0
(-7350 6125);
DISPLAY 0.680851 (-7350 6125);
PAINT MONO (-7350 6125);
DISPLAY INVISIBLE (-7350 6125);
FORCEPROP 0 LAST CDS_SEC 1
J 0
(-7350 6125);
DISPLAY 1.021277 (-7350 6125);
DISPLAY INVISIBLE (-7350 6125);
FORCEPROP 1 LASTPIN (-7400 6075) $PN 1
J 0
(-7395 6037);
DISPLAY 0.489362 (-7395 6037);
PAINT MONO (-7395 6037);
FORCEPROP 1 LASTPIN (-7400 5875) $PN 2
J 0
(-7395 5885);
DISPLAY 0.489362 (-7395 5885);
PAINT MONO (-7395 5885);
FORCEPROP 1 LAST WATTAGE 1/16W
J 0
(-7350 5950);
DISPLAY 0.489362 (-7350 5950);
PAINT SKYBLUE (-7350 5950);
FORCEPROP 1 LAST MATERIAL EMPTY
J 0
(-7350 5900);
DISPLAY 0.489362 (-7350 5900);
PAINT RED (-7350 5900);
FORCEPROP 1 LAST TOLERANCE 1%
J 0
(-7350 6000);
DISPLAY 0.489362 (-7350 6000);
PAINT SKYBLUE (-7350 6000);
FORCEPROP 1 LAST VALUE 1K
J 0
(-7350 6050);
DISPLAY 0.489362 (-7350 6050);
PAINT SKYBLUE (-7350 6050);
FORCEPROP 1 LAST PACK_TYPE 0402LF
J 0
(-7350 5800);
DISPLAY 0.489362 (-7350 5800);
PAINT SKYBLUE (-7350 5800);
FORCEPROP 1 LAST PART_NUMBER TMP_QCS21002FB24
J 0
(-7350 5850);
DISPLAY 0.489362 (-7350 5850);
PAINT SKYBLUE (-7350 5850);
FORCEPROP 2 LAST CDS_LIB pure_quanta
J 0
(-7400 5975);
DISPLAY INVISIBLE (-7400 5975);
FORCEPROP 1 LAST PATH I58
J 0
(-7350 6150);
DISPLAY 0.978723 (-7350 6150);
PAINT WHITE (-7350 6150);
DISPLAY INVISIBLE (-7350 6150);
FORCEADD VCC_CORE..1
(-8325 6275);
FORCEPROP 3 LASTPIN (-8325 6225) SIG_NAME PVDD18_S5_P0\g
J 0
(-8315 6235);
DISPLAY 0.659574 (-8315 6235);
PAINT MONO (-8315 6235);
DISPLAY INVISIBLE (-8315 6235);
FORCEPROP 1 LAST HDL_POWER PVDD18_S5_P0
J 1
(-8325 6325);
DISPLAY 0.489362 (-8325 6325);
PAINT GREEN (-8325 6325);
FORCEPROP 2 LAST CDS_LIB pure_quanta_power
J 0
(-8325 6275);
DISPLAY INVISIBLE (-8325 6275);
FORCEPROP 1 LAST PATH I59
J 0
(-8275 6300);
DISPLAY 0.872340 (-8275 6300);
PAINT AQUA (-8275 6300);
DISPLAY INVISIBLE (-8275 6300);
FORCEADD VCC_CORE..1
(-7775 2250);
FORCEPROP 3 LASTPIN (-7775 2200) SIG_NAME P3V3_STBY\g
J 0
(-7765 2210);
DISPLAY 0.659574 (-7765 2210);
PAINT MONO (-7765 2210);
DISPLAY INVISIBLE (-7765 2210);
FORCEPROP 1 LAST HDL_POWER P3V3_STBY
J 1
(-7775 2300);
DISPLAY 0.489362 (-7775 2300);
PAINT GREEN (-7775 2300);
FORCEPROP 2 LAST CDS_LIB pure_quanta_power
J 0
(-7775 2250);
DISPLAY INVISIBLE (-7775 2250);
FORCEPROP 1 LAST PATH I6
J 0
(-7725 2275);
DISPLAY 0.872340 (-7725 2275);
PAINT AQUA (-7725 2275);
DISPLAY INVISIBLE (-7725 2275);
FORCEADD Q_RES..2
(-8275 5025);
FORCEPROP 1 LAST LOCATION PR286
J 0
(-8225 5150);
DISPLAY 0.489362 (-8225 5150);
PAINT SKYBLUE (-8225 5150);
FORCEPROP 0 LAST $SEC 1
J 0
(-8225 5175);
DISPLAY 0.680851 (-8225 5175);
PAINT MONO (-8225 5175);
DISPLAY INVISIBLE (-8225 5175);
FORCEPROP 0 LAST CDS_SEC 1
J 0
(-8225 5175);
DISPLAY 1.021277 (-8225 5175);
DISPLAY INVISIBLE (-8225 5175);
FORCEPROP 1 LASTPIN (-8275 5125) $PN 1
J 0
(-8270 5087);
DISPLAY 0.489362 (-8270 5087);
PAINT MONO (-8270 5087);
FORCEPROP 1 LASTPIN (-8275 4925) $PN 2
J 0
(-8270 4935);
DISPLAY 0.489362 (-8270 4935);
PAINT MONO (-8270 4935);
FORCEPROP 1 LAST PACK_TYPE 0402LF
J 0
(-8225 4900);
DISPLAY 0.489362 (-8225 4900);
PAINT SKYBLUE (-8225 4900);
FORCEPROP 1 LAST MATERIAL EMPTY
J 0
(-8225 4950);
DISPLAY 0.489362 (-8225 4950);
PAINT RED (-8225 4950);
FORCEPROP 1 LAST WATTAGE 1/16W
J 0
(-8225 5000);
DISPLAY 0.489362 (-8225 5000);
PAINT SKYBLUE (-8225 5000);
FORCEPROP 1 LAST TOLERANCE 1%
J 0
(-8225 5050);
DISPLAY 0.489362 (-8225 5050);
PAINT SKYBLUE (-8225 5050);
FORCEPROP 1 LAST VALUE 1K
J 0
(-8225 5100);
DISPLAY 0.489362 (-8225 5100);
PAINT SKYBLUE (-8225 5100);
FORCEPROP 2 LAST CDS_LIB pure_quanta
J 0
(-8275 5025);
DISPLAY INVISIBLE (-8275 5025);
FORCEPROP 1 LAST PATH I62
J 0
(-8225 5200);
DISPLAY 0.978723 (-8225 5200);
PAINT WHITE (-8225 5200);
DISPLAY INVISIBLE (-8225 5200);
FORCEPROP 1 LAST PART_NUMBER TMP_QCS21002FB24
J 0
(-8235 4900);
DISPLAY 0.489362 (-8235 4900);
PAINT SKYBLUE (-8235 4900);
DISPLAY INVISIBLE (-8235 4900);
FORCEADD Q_RES..2
(-8525 5025);
FORCEPROP 1 LAST LOCATION PR283
J 0
(-8480 5150);
DISPLAY 0.489362 (-8480 5150);
PAINT SKYBLUE (-8480 5150);
FORCEPROP 0 LAST $SEC 1
J 0
(-8475 5175);
DISPLAY 0.680851 (-8475 5175);
PAINT MONO (-8475 5175);
DISPLAY INVISIBLE (-8475 5175);
FORCEPROP 0 LAST CDS_SEC 1
J 0
(-8475 5175);
DISPLAY 1.021277 (-8475 5175);
DISPLAY INVISIBLE (-8475 5175);
FORCEPROP 1 LASTPIN (-8525 5125) $PN 1
J 0
(-8520 5087);
DISPLAY 0.489362 (-8520 5087);
PAINT MONO (-8520 5087);
FORCEPROP 1 LASTPIN (-8525 4925) $PN 2
J 0
(-8520 4935);
DISPLAY 0.489362 (-8520 4935);
PAINT MONO (-8520 4935);
FORCEPROP 1 LAST WATTAGE 1/16W
J 0
(-8475 5000);
DISPLAY 0.489362 (-8475 5000);
PAINT SKYBLUE (-8475 5000);
FORCEPROP 1 LAST MATERIAL CHIP
J 0
(-8475 4950);
DISPLAY 0.489362 (-8475 4950);
PAINT SKYBLUE (-8475 4950);
FORCEPROP 1 LAST TOLERANCE 5%
J 0
(-8475 5050);
DISPLAY 0.489362 (-8475 5050);
PAINT SKYBLUE (-8475 5050);
FORCEPROP 1 LAST PACK_TYPE 0402LF
J 0
(-8475 4900);
DISPLAY 0.489362 (-8475 4900);
PAINT SKYBLUE (-8475 4900);
FORCEPROP 1 LAST VALUE 1K
J 0
(-8475 5100);
DISPLAY 0.489362 (-8475 5100);
PAINT SKYBLUE (-8475 5100);
FORCEPROP 2 LAST CDS_LIB pure_quanta
J 0
(-8525 5025);
DISPLAY INVISIBLE (-8525 5025);
FORCEPROP 1 LAST PATH I63
J 0
(-8475 5200);
DISPLAY 0.978723 (-8475 5200);
PAINT WHITE (-8475 5200);
DISPLAY INVISIBLE (-8475 5200);
FORCEPROP 1 LAST PART_NUMBER TMP_QCS21002JB34
J 0
(-8485 4900);
DISPLAY 0.489362 (-8485 4900);
PAINT SKYBLUE (-8485 4900);
DISPLAY INVISIBLE (-8485 4900);
FORCEADD UNIVERSAL_GND..1
(-8525 4775);
FORCEPROP 3 LASTPIN (-8525 4825) SIG_NAME GND\g
J 0
(-8515 4835);
DISPLAY 0.659574 (-8515 4835);
PAINT MONO (-8515 4835);
DISPLAY INVISIBLE (-8515 4835);
FORCEPROP 2 LAST CDS_LIB pure_quanta_power
J 0
(-8525 4775);
DISPLAY INVISIBLE (-8525 4775);
FORCEPROP 1 LAST PATH I64
J 0
(-8450 4775);
DISPLAY 0.872340 (-8450 4775);
PAINT AQUA (-8450 4775);
DISPLAY INVISIBLE (-8450 4775);
FORCEPROP 1 LAST HDL_POWER GND
J 1
(-8500 4700);
DISPLAY 0.872340 (-8500 4700);
PAINT GREEN (-8500 4700);
DISPLAY INVISIBLE (-8500 4700);
FORCEADD UNIVERSAL_GND..1
(-8275 4775);
FORCEPROP 3 LASTPIN (-8275 4825) SIG_NAME GND\g
J 0
(-8265 4835);
DISPLAY 0.659574 (-8265 4835);
PAINT MONO (-8265 4835);
DISPLAY INVISIBLE (-8265 4835);
FORCEPROP 2 LAST CDS_LIB pure_quanta_power
J 0
(-8275 4775);
DISPLAY INVISIBLE (-8275 4775);
FORCEPROP 1 LAST PATH I65
J 0
(-8200 4775);
DISPLAY 0.872340 (-8200 4775);
PAINT AQUA (-8200 4775);
DISPLAY INVISIBLE (-8200 4775);
FORCEPROP 1 LAST HDL_POWER GND
J 1
(-8250 4700);
DISPLAY 0.872340 (-8250 4700);
PAINT GREEN (-8250 4700);
DISPLAY INVISIBLE (-8250 4700);
FORCEADD Q_RES..1
(-5925 4950);
FORCEPROP 1 LAST LOCATION PR308
J 0
(-5975 5000);
DISPLAY 0.489362 (-5975 5000);
PAINT SKYBLUE (-5975 5000);
FORCEPROP 0 LAST $SEC 1
J 0
(-5975 5025);
DISPLAY 0.680851 (-5975 5025);
PAINT MONO (-5975 5025);
DISPLAY INVISIBLE (-5975 5025);
FORCEPROP 0 LAST CDS_SEC 1
J 0
(-5975 5025);
DISPLAY 1.021277 (-5975 5025);
DISPLAY INVISIBLE (-5975 5025);
FORCEPROP 1 LASTPIN (-6025 4950) $PN 1
J 0
(-6013 4962);
DISPLAY 0.489362 (-6013 4962);
PAINT MONO (-6013 4962);
FORCEPROP 1 LASTPIN (-5825 4950) $PN 2
J 0
(-5863 4962);
DISPLAY 0.489362 (-5863 4962);
PAINT MONO (-5863 4962);
FORCEPROP 1 LAST PART_NUMBER CS00002JB38
J 0
(-6175 4900);
DISPLAY 0.489362 (-6175 4900);
PAINT SKYBLUE (-6175 4900);
FORCEPROP 1 LAST MATERIAL CHIP
J 0
(-6175 4875);
DISPLAY 0.489362 (-6175 4875);
PAINT SKYBLUE (-6175 4875);
FORCEPROP 1 LAST TOLERANCE 5%
J 0
(-5800 4975);
DISPLAY 0.489362 (-5800 4975);
PAINT SKYBLUE (-5800 4975);
FORCEPROP 1 LAST PACK_TYPE 0402LF
J 0
(-5825 4875);
DISPLAY 0.489362 (-5825 4875);
PAINT SKYBLUE (-5825 4875);
FORCEPROP 1 LAST WATTAGE 1/16W
J 0
(-5825 4900);
DISPLAY 0.489362 (-5825 4900);
PAINT SKYBLUE (-5825 4900);
FORCEPROP 1 LAST VALUE 0
J 2
(-6050 4975);
DISPLAY 0.489362 (-6050 4975);
PAINT SKYBLUE (-6050 4975);
FORCEPROP 2 LAST CDS_LIB pure_quanta
J 0
(-5925 4950);
DISPLAY INVISIBLE (-5925 4950);
FORCEPROP 1 LAST PATH I66
J 0
(-5975 5100);
DISPLAY 0.978723 (-5975 5100);
PAINT WHITE (-5975 5100);
DISPLAY INVISIBLE (-5975 5100);
FORCEADD Q_RES..1
(-5925 4800);
FORCEPROP 1 LAST LOCATION PR309
J 0
(-5975 4850);
DISPLAY 0.489362 (-5975 4850);
PAINT SKYBLUE (-5975 4850);
FORCEPROP 0 LAST $SEC 1
J 0
(-5975 4875);
DISPLAY 0.680851 (-5975 4875);
PAINT MONO (-5975 4875);
DISPLAY INVISIBLE (-5975 4875);
FORCEPROP 0 LAST CDS_SEC 1
J 0
(-5975 4875);
DISPLAY 1.021277 (-5975 4875);
DISPLAY INVISIBLE (-5975 4875);
FORCEPROP 1 LASTPIN (-6025 4800) $PN 1
J 0
(-6013 4812);
DISPLAY 0.489362 (-6013 4812);
PAINT MONO (-6013 4812);
FORCEPROP 1 LASTPIN (-5825 4800) $PN 2
J 0
(-5863 4812);
DISPLAY 0.489362 (-5863 4812);
PAINT MONO (-5863 4812);
FORCEPROP 1 LAST VALUE 0
J 2
(-6050 4825);
DISPLAY 0.489362 (-6050 4825);
PAINT SKYBLUE (-6050 4825);
FORCEPROP 1 LAST PART_NUMBER CS00002JB38
J 0
(-6175 4750);
DISPLAY 0.489362 (-6175 4750);
PAINT SKYBLUE (-6175 4750);
FORCEPROP 1 LAST MATERIAL CHIP
J 0
(-6175 4725);
DISPLAY 0.489362 (-6175 4725);
PAINT SKYBLUE (-6175 4725);
FORCEPROP 1 LAST PACK_TYPE 0402LF
J 0
(-5825 4725);
DISPLAY 0.489362 (-5825 4725);
PAINT SKYBLUE (-5825 4725);
FORCEPROP 1 LAST WATTAGE 1/16W
J 0
(-5825 4750);
DISPLAY 0.489362 (-5825 4750);
PAINT SKYBLUE (-5825 4750);
FORCEPROP 1 LAST TOLERANCE 5%
J 0
(-5800 4825);
DISPLAY 0.489362 (-5800 4825);
PAINT SKYBLUE (-5800 4825);
FORCEPROP 2 LAST CDS_LIB pure_quanta
J 0
(-5925 4800);
DISPLAY INVISIBLE (-5925 4800);
FORCEPROP 1 LAST PATH I67
J 0
(-5975 4950);
DISPLAY 0.978723 (-5975 4950);
PAINT WHITE (-5975 4950);
DISPLAY INVISIBLE (-5975 4950);
FORCEADD Q_RES..1
(-5925 4650);
FORCEPROP 1 LAST LOCATION PR310
J 0
(-5975 4700);
DISPLAY 0.489362 (-5975 4700);
PAINT SKYBLUE (-5975 4700);
FORCEPROP 0 LAST $SEC 1
J 0
(-5975 4725);
DISPLAY 0.680851 (-5975 4725);
PAINT MONO (-5975 4725);
DISPLAY INVISIBLE (-5975 4725);
FORCEPROP 0 LAST CDS_SEC 1
J 0
(-5975 4725);
DISPLAY 1.021277 (-5975 4725);
DISPLAY INVISIBLE (-5975 4725);
FORCEPROP 1 LASTPIN (-6025 4650) $PN 1
J 0
(-6013 4662);
DISPLAY 0.489362 (-6013 4662);
PAINT MONO (-6013 4662);
FORCEPROP 1 LASTPIN (-5825 4650) $PN 2
J 0
(-5863 4662);
DISPLAY 0.489362 (-5863 4662);
PAINT MONO (-5863 4662);
FORCEPROP 1 LAST PART_NUMBER CS00002JB38
J 0
(-6175 4600);
DISPLAY 0.489362 (-6175 4600);
PAINT SKYBLUE (-6175 4600);
FORCEPROP 1 LAST TOLERANCE 5%
J 0
(-5800 4675);
DISPLAY 0.489362 (-5800 4675);
PAINT SKYBLUE (-5800 4675);
FORCEPROP 1 LAST VALUE 0
J 2
(-6050 4675);
DISPLAY 0.489362 (-6050 4675);
PAINT SKYBLUE (-6050 4675);
FORCEPROP 1 LAST MATERIAL CHIP
J 0
(-6175 4575);
DISPLAY 0.489362 (-6175 4575);
PAINT SKYBLUE (-6175 4575);
FORCEPROP 1 LAST WATTAGE 1/16W
J 0
(-5825 4600);
DISPLAY 0.489362 (-5825 4600);
PAINT SKYBLUE (-5825 4600);
FORCEPROP 1 LAST PACK_TYPE 0402LF
J 0
(-5825 4575);
DISPLAY 0.489362 (-5825 4575);
PAINT SKYBLUE (-5825 4575);
FORCEPROP 2 LAST CDS_LIB pure_quanta
J 0
(-5925 4650);
DISPLAY INVISIBLE (-5925 4650);
FORCEPROP 1 LAST PATH I68
J 0
(-5975 4800);
DISPLAY 0.978723 (-5975 4800);
PAINT WHITE (-5975 4800);
DISPLAY INVISIBLE (-5975 4800);
FORCEADD RAA229620GNPHA0..1
(-4325 3350);
FORCEPROP 1 LAST LOCATION PU42
J 0
(-4875 6375);
DISPLAY 0.489362 (-4875 6375);
PAINT SKYBLUE (-4875 6375);
FORCEPROP 2 LAST SEC 1
J 0
(-4875 6550);
DISPLAY 0.680851 (-4875 6550);
PAINT MONO (-4875 6550);
DISPLAY INVISIBLE (-4875 6550);
FORCEPROP 2 LASTPIN (-3675 1700) $PN 38
J 0
(-3665 1710);
DISPLAY 0.489362 (-3665 1710);
PAINT MONO (-3665 1710);
FORCEPROP 2 LASTPIN (-3675 2000) $PN 37
J 0
(-3665 2010);
DISPLAY 0.489362 (-3665 2010);
PAINT MONO (-3665 2010);
FORCEPROP 2 LASTPIN (-3675 2300) $PN 36
J 0
(-3665 2310);
DISPLAY 0.489362 (-3665 2310);
PAINT MONO (-3665 2310);
FORCEPROP 2 LASTPIN (-3675 2600) $PN 35
J 0
(-3665 2610);
DISPLAY 0.489362 (-3665 2610);
PAINT MONO (-3665 2610);
FORCEPROP 2 LASTPIN (-3675 2900) $PN 34
J 0
(-3665 2910);
DISPLAY 0.489362 (-3665 2910);
PAINT MONO (-3665 2910);
FORCEPROP 2 LASTPIN (-3675 3200) $PN 33
J 0
(-3665 3210);
DISPLAY 0.489362 (-3665 3210);
PAINT MONO (-3665 3210);
FORCEPROP 2 LASTPIN (-3675 3500) $PN 32
J 0
(-3665 3510);
DISPLAY 0.489362 (-3665 3510);
PAINT MONO (-3665 3510);
FORCEPROP 2 LASTPIN (-3675 3800) $PN 31
J 0
(-3665 3810);
DISPLAY 0.489362 (-3665 3810);
PAINT MONO (-3665 3810);
FORCEPROP 2 LASTPIN (-3675 4100) $PN 30
J 0
(-3665 4110);
DISPLAY 0.489362 (-3665 4110);
PAINT MONO (-3665 4110);
FORCEPROP 2 LASTPIN (-3675 4400) $PN 29
J 0
(-3665 4410);
DISPLAY 0.489362 (-3665 4410);
PAINT MONO (-3665 4410);
FORCEPROP 2 LASTPIN (-3675 4700) $PN 28
J 0
(-3665 4710);
DISPLAY 0.489362 (-3665 4710);
PAINT MONO (-3665 4710);
FORCEPROP 2 LASTPIN (-3675 5000) $PN 27
J 0
(-3665 5010);
DISPLAY 0.489362 (-3665 5010);
PAINT MONO (-3665 5010);
FORCEPROP 2 LASTPIN (-5025 5950) $PN 17
J 2
(-5035 5960);
DISPLAY 0.489362 (-5035 5960);
PAINT MONO (-5035 5960);
FORCEPROP 2 LASTPIN (-5025 1350) $PN 42
J 2
(-5035 1360);
DISPLAY 0.489362 (-5035 1360);
PAINT MONO (-5035 1360);
FORCEPROP 2 LASTPIN (-5025 4650) $PN 15
J 2
(-5035 4660);
DISPLAY 0.489362 (-5035 4660);
PAINT MONO (-5035 4660);
FORCEPROP 2 LASTPIN (-5025 2100) $PN 41
J 2
(-5035 2110);
DISPLAY 0.489362 (-5035 2110);
PAINT MONO (-5035 2110);
FORCEPROP 2 LASTPIN (-5025 6100) $PN 16
J 2
(-5035 6110);
DISPLAY 0.489362 (-5035 6110);
PAINT MONO (-5035 6110);
FORCEPROP 2 LASTPIN (-5025 850) $PN 20
J 2
(-5035 860);
DISPLAY 0.489362 (-5035 860);
PAINT MONO (-5035 860);
FORCEPROP 2 LASTPIN (-5025 4950) $PN 14
J 2
(-5035 4960);
DISPLAY 0.489362 (-5035 4960);
PAINT MONO (-5035 4960);
FORCEPROP 2 LASTPIN (-5025 4800) $PN 13
J 2
(-5035 4810);
DISPLAY 0.489362 (-5035 4810);
PAINT MONO (-5035 4810);
FORCEPROP 2 LASTPIN (-3675 1800) $PN 1
J 0
(-3665 1810);
DISPLAY 0.489362 (-3665 1810);
PAINT MONO (-3665 1810);
FORCEPROP 2 LASTPIN (-3675 2100) $PN 2
J 0
(-3665 2110);
DISPLAY 0.489362 (-3665 2110);
PAINT MONO (-3665 2110);
FORCEPROP 2 LASTPIN (-3675 2400) $PN 3
J 0
(-3665 2410);
DISPLAY 0.489362 (-3665 2410);
PAINT MONO (-3665 2410);
FORCEPROP 2 LASTPIN (-3675 2700) $PN 4
J 0
(-3665 2710);
DISPLAY 0.489362 (-3665 2710);
PAINT MONO (-3665 2710);
FORCEPROP 2 LASTPIN (-3675 3000) $PN 5
J 0
(-3665 3010);
DISPLAY 0.489362 (-3665 3010);
PAINT MONO (-3665 3010);
FORCEPROP 2 LASTPIN (-3675 3300) $PN 6
J 0
(-3665 3310);
DISPLAY 0.489362 (-3665 3310);
PAINT MONO (-3665 3310);
FORCEPROP 2 LASTPIN (-3675 3600) $PN 7
J 0
(-3665 3610);
DISPLAY 0.489362 (-3665 3610);
PAINT MONO (-3665 3610);
FORCEPROP 2 LASTPIN (-3675 3900) $PN 8
J 0
(-3665 3910);
DISPLAY 0.489362 (-3665 3910);
PAINT MONO (-3665 3910);
FORCEPROP 2 LASTPIN (-3675 4200) $PN 9
J 0
(-3665 4210);
DISPLAY 0.489362 (-3665 4210);
PAINT MONO (-3665 4210);
FORCEPROP 2 LASTPIN (-3675 4500) $PN 10
J 0
(-3665 4510);
DISPLAY 0.489362 (-3665 4510);
PAINT MONO (-3665 4510);
FORCEPROP 2 LASTPIN (-3675 4800) $PN 11
J 0
(-3665 4810);
DISPLAY 0.489362 (-3665 4810);
PAINT MONO (-3665 4810);
FORCEPROP 2 LASTPIN (-3675 5100) $PN 12
J 0
(-3665 5110);
DISPLAY 0.489362 (-3665 5110);
PAINT MONO (-3665 5110);
FORCEPROP 2 LASTPIN (-5025 2250) $PN 18
J 2
(-5035 2260);
DISPLAY 0.489362 (-5035 2260);
PAINT MONO (-5035 2260);
FORCEPROP 2 LASTPIN (-5025 3800) $PN 26
J 2
(-5035 3810);
DISPLAY 0.489362 (-5035 3810);
PAINT MONO (-5035 3810);
FORCEPROP 2 LASTPIN (-5025 2700) $PN 39
J 2
(-5035 2710);
DISPLAY 0.489362 (-5035 2710);
PAINT MONO (-5035 2710);
FORCEPROP 2 LASTPIN (-5025 5650) $PN 22
J 2
(-5035 5660);
DISPLAY 0.489362 (-5035 5660);
PAINT MONO (-5035 5660);
FORCEPROP 2 LASTPIN (-5025 5500) $PN 21
J 2
(-5035 5510);
DISPLAY 0.489362 (-5035 5510);
PAINT MONO (-5035 5510);
FORCEPROP 2 LASTPIN (-5025 5200) $PN 24
J 2
(-5035 5210);
DISPLAY 0.489362 (-5035 5210);
PAINT MONO (-5035 5210);
FORCEPROP 2 LASTPIN (-5025 5350) $PN 23
J 2
(-5035 5360);
DISPLAY 0.489362 (-5035 5360);
PAINT MONO (-5035 5360);
FORCEPROP 2 LASTPIN (-3675 900) $PN 44
J 0
(-3665 910);
DISPLAY 0.489362 (-3665 910);
PAINT MONO (-3665 910);
FORCEPROP 2 LASTPIN (-3675 1200) $PN 43
J 0
(-3665 1210);
DISPLAY 0.489362 (-3665 1210);
PAINT MONO (-3665 1210);
FORCEPROP 2 LASTPIN (-5025 550) $PN TH
J 2
(-5035 560);
DISPLAY 0.489362 (-5035 560);
PAINT MONO (-5035 560);
FORCEPROP 2 LASTPIN (-3675 6100) $PN 47
J 0
(-3665 6110);
DISPLAY 0.489362 (-3665 6110);
PAINT MONO (-3665 6110);
FORCEPROP 2 LASTPIN (-3675 5800) $PN 48
J 0
(-3665 5810);
DISPLAY 0.489362 (-3665 5810);
PAINT MONO (-3665 5810);
FORCEPROP 2 LASTPIN (-5025 1850) $PN 19
J 2
(-5035 1860);
DISPLAY 0.489362 (-5035 1860);
PAINT MONO (-5035 1860);
FORCEPROP 2 LASTPIN (-5025 650) $PN 46
J 2
(-5035 660);
DISPLAY 0.489362 (-5035 660);
PAINT MONO (-5035 660);
FORCEPROP 2 LASTPIN (-5025 750) $PN 45
J 2
(-5035 760);
DISPLAY 0.489362 (-5035 760);
PAINT MONO (-5035 760);
FORCEPROP 2 LASTPIN (-5025 4050) $PN 25
J 2
(-5035 4060);
DISPLAY 0.489362 (-5035 4060);
PAINT MONO (-5035 4060);
FORCEPROP 2 LASTPIN (-5025 2950) $PN 40
J 2
(-5035 2960);
DISPLAY 0.489362 (-5035 2960);
PAINT MONO (-5035 2960);
FORCEPROP 2 LAST PART_TYPE SMLF
J 0
(-4875 6500);
DISPLAY 1.021277 (-4875 6500);
FORCEPROP 2 LAST VALUE RAA229620GNP#HA0
J 0
(-4875 6450);
DISPLAY 0.489362 (-4875 6450);
PAINT SKYBLUE (-4875 6450);
FORCEPROP 1 LAST MATERIAL IC
J 0
(-4875 6225);
DISPLAY 0.489362 (-4875 6225);
PAINT SKYBLUE (-4875 6225);
FORCEPROP 1 LAST PART_NUMBER AR0T6GPV005
J 0
(-4875 6300);
DISPLAY 0.489362 (-4875 6300);
PAINT SKYBLUE (-4875 6300);
FORCEPROP 2 LAST SEC_TYPE 
J 0
(-4875 6550);
DISPLAY 1.021277 (-4875 6550);
DISPLAY INVISIBLE (-4875 6550);
FORCEPROP 2 LAST CDS_LIB pure_quanta
J 0
(-4325 3350);
DISPLAY INVISIBLE (-4325 3350);
FORCEPROP 1 LAST NEEDS_NO_SIZE TRUE
J 0
(-4325 3350);
DISPLAY 0.723404 (-4325 3350);
PAINT GREEN (-4325 3350);
DISPLAY INVISIBLE (-4325 3350);
FORCEPROP 1 LAST CDS_LMAN_SYM_OUTLINE -550,2850,500,-2850
J 0
(-4325 3350);
DISPLAY 0.468085 (-4325 3350);
PAINT GREEN (-4325 3350);
DISPLAY INVISIBLE (-4325 3350);
FORCEPROP 1 LAST PATH I7
J 0
(-4325 3350);
DISPLAY 0.723404 (-4325 3350);
PAINT GREEN (-4325 3350);
DISPLAY INVISIBLE (-4325 3350);
FORCEADD OFFPAGE..4
R 2
(-6750 4950);
FORCEPROP 2 LAST $XR0 118 
J 0
(-7002 4950);
DISPLAY 0.638298 (-7002 4950);
PAINT MONO (-7002 4950);
FORCEPROP 2 LAST CDS_LIB standard
J 0
(-6750 4950);
DISPLAY INVISIBLE (-6750 4950);
FORCEPROP 1 LAST OFFPAGE TRUE
J 2
(-7075 4825);
DISPLAY 0.872340 (-7075 4825);
PAINT GREEN (-7075 4825);
DISPLAY INVISIBLE (-7075 4825);
FORCEPROP 1 LAST COMMENT_BODY TRUE
J 2
(-6725 4850);
DISPLAY 0.872340 (-6725 4850);
PAINT GREEN (-6725 4850);
DISPLAY INVISIBLE (-6725 4850);
FORCEPROP 2 LAST PATH I73
J 0
(-6700 5025);
DISPLAY 1.021277 (-6700 5025);
DISPLAY INVISIBLE (-6700 5025);
FORCEADD OFFPAGE..3
R 2
(-6750 4800);
FORCEPROP 2 LAST $XR0 118 
J 0
(-7030 4800);
DISPLAY 0.638298 (-7030 4800);
PAINT MONO (-7030 4800);
FORCEPROP 2 LAST CDS_LIB standard
J 0
(-6750 4800);
DISPLAY INVISIBLE (-6750 4800);
FORCEPROP 1 LAST OFFPAGE TRUE
J 2
(-7075 4675);
DISPLAY 0.872340 (-7075 4675);
PAINT GREEN (-7075 4675);
DISPLAY INVISIBLE (-7075 4675);
FORCEPROP 1 LAST COMMENT_BODY TRUE
J 2
(-6700 4700);
DISPLAY 0.872340 (-6700 4700);
PAINT GREEN (-6700 4700);
DISPLAY INVISIBLE (-6700 4700);
FORCEPROP 2 LAST PATH I74
J 0
(-6700 4875);
DISPLAY 1.021277 (-6700 4875);
DISPLAY INVISIBLE (-6700 4875);
FORCEADD OFFPAGE..2
R 2
(-6800 4650);
FORCEPROP 2 LAST $XR1 80 
J 0
(-7114 4650);
DISPLAY 0.638298 (-7114 4650);
PAINT MONO (-7114 4650);
FORCEPROP 2 LAST $XR0 82 
J 0
(-7024 4650);
DISPLAY 0.638298 (-7024 4650);
PAINT MONO (-7024 4650);
FORCEPROP 2 LAST CDS_LIB standard
J 0
(-6800 4650);
DISPLAY INVISIBLE (-6800 4650);
FORCEPROP 1 LAST OFFPAGE TRUE
J 2
(-7125 4525);
DISPLAY 0.872340 (-7125 4525);
PAINT GREEN (-7125 4525);
DISPLAY INVISIBLE (-7125 4525);
FORCEPROP 1 LAST COMMENT_BODY TRUE
J 2
(-6755 4555);
DISPLAY 0.872340 (-6755 4555);
PAINT GREEN (-6755 4555);
DISPLAY INVISIBLE (-6755 4555);
FORCEPROP 2 LAST PATH I75
J 0
(-6750 4725);
DISPLAY 1.021277 (-6750 4725);
DISPLAY INVISIBLE (-6750 4725);
FORCEADD Q_CAP..1
(-5750 3925);
FORCEPROP 1 LAST LOCATION PC463
J 0
(-5700 3975);
DISPLAY 0.489362 (-5700 3975);
PAINT SKYBLUE (-5700 3975);
FORCEPROP 0 LAST $SEC 1
J 0
(-5700 4000);
DISPLAY 0.680851 (-5700 4000);
PAINT MONO (-5700 4000);
DISPLAY INVISIBLE (-5700 4000);
FORCEPROP 0 LAST CDS_SEC 1
J 0
(-5700 4000);
DISPLAY 1.021277 (-5700 4000);
DISPLAY INVISIBLE (-5700 4000);
FORCEPROP 1 LASTPIN (-5750 4025) $PN 1
J 0
(-5740 4005);
DISPLAY 0.489362 (-5740 4005);
PAINT MONO (-5740 4005);
FORCEPROP 1 LASTPIN (-5750 3825) $PN 2
J 0
(-5740 3805);
DISPLAY 0.489362 (-5740 3805);
PAINT MONO (-5740 3805);
FORCEPROP 1 LAST PART_NUMBER TMP_QCH2336K1B12
J 0
(-5700 3850);
DISPLAY 0.489362 (-5700 3850);
PAINT SKYBLUE (-5700 3850);
FORCEPROP 1 LAST PACK_TYPE 0402
J 0
(-5700 3825);
DISPLAY 0.489362 (-5700 3825);
PAINT SKYBLUE (-5700 3825);
FORCEPROP 1 LAST MATERIAL X7R
J 0
(-5700 3875);
DISPLAY 0.489362 (-5700 3875);
PAINT SKYBLUE (-5700 3875);
FORCEPROP 1 LAST VALUE 3300PF
J 0
(-5700 3950);
DISPLAY 0.489362 (-5700 3950);
PAINT SKYBLUE (-5700 3950);
FORCEPROP 1 LAST VOLTAGE 50V
J 0
(-5700 3925);
DISPLAY 0.489362 (-5700 3925);
PAINT SKYBLUE (-5700 3925);
FORCEPROP 1 LAST TOLERANCE 10%
J 0
(-5700 3900);
DISPLAY 0.489362 (-5700 3900);
PAINT SKYBLUE (-5700 3900);
FORCEPROP 2 LAST CDS_LIB pure_quanta
J 0
(-5750 3925);
DISPLAY INVISIBLE (-5750 3925);
FORCEPROP 1 LAST PATH I76
J 0
(-5700 4075);
DISPLAY 0.978723 (-5700 4075);
PAINT WHITE (-5700 4075);
DISPLAY INVISIBLE (-5700 4075);
FORCEADD Q_RES..1
(-6025 4050);
FORCEPROP 1 LAST LOCATION PR306
J 0
(-6075 4100);
DISPLAY 0.489362 (-6075 4100);
PAINT SKYBLUE (-6075 4100);
FORCEPROP 0 LAST $SEC 1
J 0
(-6075 4125);
DISPLAY 0.680851 (-6075 4125);
PAINT MONO (-6075 4125);
DISPLAY INVISIBLE (-6075 4125);
FORCEPROP 0 LAST CDS_SEC 1
J 0
(-6075 4125);
DISPLAY 1.021277 (-6075 4125);
DISPLAY INVISIBLE (-6075 4125);
FORCEPROP 1 LASTPIN (-6125 4050) $PN 1
J 0
(-6113 4062);
DISPLAY 0.489362 (-6113 4062);
PAINT MONO (-6113 4062);
FORCEPROP 1 LASTPIN (-5925 4050) $PN 2
J 0
(-5963 4062);
DISPLAY 0.489362 (-5963 4062);
PAINT MONO (-5963 4062);
FORCEPROP 1 LAST PACK_TYPE 0402LF
J 0
(-5925 3975);
DISPLAY 0.489362 (-5925 3975);
PAINT SKYBLUE (-5925 3975);
FORCEPROP 1 LAST PART_NUMBER TMP_QCS01002FB21
J 0
(-6350 4000);
DISPLAY 0.489362 (-6350 4000);
PAINT SKYBLUE (-6350 4000);
FORCEPROP 1 LAST VALUE 10
J 2
(-6150 4075);
DISPLAY 0.489362 (-6150 4075);
PAINT SKYBLUE (-6150 4075);
FORCEPROP 1 LAST MATERIAL CHIP
J 0
(-6350 3975);
DISPLAY 0.489362 (-6350 3975);
PAINT SKYBLUE (-6350 3975);
FORCEPROP 1 LAST TOLERANCE 1%
J 0
(-5900 4075);
DISPLAY 0.489362 (-5900 4075);
PAINT SKYBLUE (-5900 4075);
FORCEPROP 1 LAST WATTAGE 1/16W
J 0
(-5925 4000);
DISPLAY 0.489362 (-5925 4000);
PAINT SKYBLUE (-5925 4000);
FORCEPROP 2 LAST CDS_LIB pure_quanta
J 0
(-6025 4050);
DISPLAY INVISIBLE (-6025 4050);
FORCEPROP 1 LAST PATH I77
J 0
(-6075 4200);
DISPLAY 0.978723 (-6075 4200);
PAINT WHITE (-6075 4200);
DISPLAY INVISIBLE (-6075 4200);
FORCEADD OFFPAGE..4
R 2
(-7800 4050);
FORCEPROP 2 LAST $XR0 27 
J 0
(-8081 4050);
DISPLAY 0.638298 (-8081 4050);
PAINT MONO (-8081 4050);
FORCEPROP 2 LAST CDS_LIB standard
J 2
(-7800 4050);
DISPLAY INVISIBLE (-7800 4050);
FORCEPROP 1 LAST OFFPAGE TRUE
J 2
(-8125 3925);
DISPLAY 0.872340 (-8125 3925);
PAINT GREEN (-8125 3925);
DISPLAY INVISIBLE (-8125 3925);
FORCEPROP 1 LAST COMMENT_BODY TRUE
J 2
(-7775 3950);
DISPLAY 0.872340 (-7775 3950);
PAINT GREEN (-7775 3950);
DISPLAY INVISIBLE (-7775 3950);
FORCEPROP 2 LAST PATH I79
J 2
(-7975 4125);
DISPLAY 1.021277 (-7975 4125);
DISPLAY INVISIBLE (-7975 4125);
FORCEADD Q_CAP..1
(-2900 6125);
FORCEPROP 1 LAST LOCATION PC471
J 0
(-2850 6225);
DISPLAY 0.489362 (-2850 6225);
PAINT SKYBLUE (-2850 6225);
FORCEPROP 0 LAST $SEC 1
J 0
(-2850 6250);
DISPLAY 0.680851 (-2850 6250);
PAINT MONO (-2850 6250);
DISPLAY INVISIBLE (-2850 6250);
FORCEPROP 0 LAST CDS_SEC 1
J 0
(-2850 6250);
DISPLAY 1.021277 (-2850 6250);
DISPLAY INVISIBLE (-2850 6250);
FORCEPROP 1 LASTPIN (-2900 6225) $PN 1
J 0
(-2890 6205);
DISPLAY 0.489362 (-2890 6205);
PAINT MONO (-2890 6205);
FORCEPROP 1 LASTPIN (-2900 6025) $PN 2
J 0
(-2890 6005);
DISPLAY 0.489362 (-2890 6005);
PAINT MONO (-2890 6005);
FORCEPROP 1 LAST MATERIAL X6S
J 0
(-2850 6025);
DISPLAY 0.489362 (-2850 6025);
PAINT SKYBLUE (-2850 6025);
FORCEPROP 1 LAST TOLERANCE 10%
J 0
(-2850 6075);
DISPLAY 0.489362 (-2850 6075);
PAINT SKYBLUE (-2850 6075);
FORCEPROP 1 LAST VALUE 1UF
J 0
(-2850 6175);
DISPLAY 0.489362 (-2850 6175);
PAINT SKYBLUE (-2850 6175);
FORCEPROP 1 LAST PART_NUMBER CH5103KEB01
J 0
(-2850 5975);
DISPLAY 0.489362 (-2850 5975);
PAINT SKYBLUE (-2850 5975);
FORCEPROP 1 LAST VOLTAGE 16V
J 0
(-2850 6125);
DISPLAY 0.489362 (-2850 6125);
PAINT SKYBLUE (-2850 6125);
FORCEPROP 1 LAST PACK_TYPE C0402
J 0
(-2850 5925);
DISPLAY 0.489362 (-2850 5925);
PAINT SKYBLUE (-2850 5925);
FORCEPROP 2 LAST CDS_LIB pure_quanta
J 0
(-2900 6125);
DISPLAY INVISIBLE (-2900 6125);
FORCEPROP 1 LAST PATH I8
J 0
(-2850 6275);
DISPLAY 0.978723 (-2850 6275);
PAINT WHITE (-2850 6275);
DISPLAY INVISIBLE (-2850 6275);
FORCEADD OFFPAGE..4
R 2
(-7800 3800);
FORCEPROP 2 LAST $XR1 169 
J 0
(-8201 3800);
DISPLAY 0.638298 (-8201 3800);
PAINT MONO (-8201 3800);
FORCEPROP 2 LAST $XR0 27 
J 0
(-8081 3800);
DISPLAY 0.638298 (-8081 3800);
PAINT MONO (-8081 3800);
FORCEPROP 2 LAST CDS_LIB standard
J 0
(-7800 3800);
DISPLAY INVISIBLE (-7800 3800);
FORCEPROP 1 LAST OFFPAGE TRUE
J 2
(-8125 3675);
DISPLAY 0.872340 (-8125 3675);
PAINT GREEN (-8125 3675);
DISPLAY INVISIBLE (-8125 3675);
FORCEPROP 1 LAST COMMENT_BODY TRUE
J 2
(-7775 3700);
DISPLAY 0.872340 (-7775 3700);
PAINT GREEN (-7775 3700);
DISPLAY INVISIBLE (-7775 3700);
FORCEPROP 2 LAST PATH I80
J 0
(-7750 3875);
DISPLAY 1.021277 (-7750 3875);
DISPLAY INVISIBLE (-7750 3875);
FORCEADD Q_RES..2
(-7050 4250);
FORCEPROP 1 LAST LOCATION PR294
J 0
(-7000 4375);
DISPLAY 0.489362 (-7000 4375);
PAINT SKYBLUE (-7000 4375);
FORCEPROP 0 LAST $SEC 1
J 0
(-7000 4400);
DISPLAY 0.680851 (-7000 4400);
PAINT MONO (-7000 4400);
DISPLAY INVISIBLE (-7000 4400);
FORCEPROP 0 LAST CDS_SEC 1
J 0
(-7000 4400);
DISPLAY 1.021277 (-7000 4400);
DISPLAY INVISIBLE (-7000 4400);
FORCEPROP 1 LASTPIN (-7050 4350) $PN 1
J 0
(-7045 4312);
DISPLAY 0.489362 (-7045 4312);
PAINT MONO (-7045 4312);
FORCEPROP 1 LASTPIN (-7050 4150) $PN 2
J 0
(-7045 4160);
DISPLAY 0.489362 (-7045 4160);
PAINT MONO (-7045 4160);
FORCEPROP 1 LAST WATTAGE 1/16W
J 0
(-7000 4225);
DISPLAY 0.489362 (-7000 4225);
PAINT SKYBLUE (-7000 4225);
FORCEPROP 1 LAST PART_NUMBER CS04992FB31
J 0
(-7000 4125);
DISPLAY 0.489362 (-7000 4125);
PAINT SKYBLUE (-7000 4125);
FORCEPROP 1 LAST MATERIAL CHIP
J 0
(-7000 4175);
DISPLAY 0.489362 (-7000 4175);
PAINT SKYBLUE (-7000 4175);
FORCEPROP 1 LAST PACK_TYPE 0402LF
J 0
(-7000 4075);
DISPLAY 0.489362 (-7000 4075);
PAINT SKYBLUE (-7000 4075);
FORCEPROP 1 LAST VALUE 49.9
J 0
(-7000 4325);
DISPLAY 0.489362 (-7000 4325);
PAINT SKYBLUE (-7000 4325);
FORCEPROP 1 LAST TOLERANCE 1%
J 0
(-7000 4275);
DISPLAY 0.489362 (-7000 4275);
PAINT SKYBLUE (-7000 4275);
FORCEPROP 2 LAST CDS_LIB pure_quanta
J 0
(-7050 4250);
DISPLAY INVISIBLE (-7050 4250);
FORCEPROP 1 LAST PATH I81
J 0
(-7000 4425);
DISPLAY 0.978723 (-7000 4425);
PAINT WHITE (-7000 4425);
DISPLAY INVISIBLE (-7000 4425);
FORCEADD Q_RES..2
(-7050 3625);
FORCEPROP 1 LAST LOCATION PR295
J 0
(-7000 3750);
DISPLAY 0.489362 (-7000 3750);
PAINT SKYBLUE (-7000 3750);
FORCEPROP 0 LAST $SEC 1
J 0
(-7000 3775);
DISPLAY 0.680851 (-7000 3775);
PAINT MONO (-7000 3775);
DISPLAY INVISIBLE (-7000 3775);
FORCEPROP 0 LAST CDS_SEC 1
J 0
(-7000 3775);
DISPLAY 1.021277 (-7000 3775);
DISPLAY INVISIBLE (-7000 3775);
FORCEPROP 1 LASTPIN (-7050 3725) $PN 1
J 0
(-7045 3687);
DISPLAY 0.489362 (-7045 3687);
PAINT MONO (-7045 3687);
FORCEPROP 1 LASTPIN (-7050 3525) $PN 2
J 0
(-7045 3535);
DISPLAY 0.489362 (-7045 3535);
PAINT MONO (-7045 3535);
FORCEPROP 1 LAST PACK_TYPE 0402LF
J 0
(-7000 3450);
DISPLAY 0.489362 (-7000 3450);
PAINT SKYBLUE (-7000 3450);
FORCEPROP 1 LAST WATTAGE 1/16W
J 0
(-7000 3600);
DISPLAY 0.489362 (-7000 3600);
PAINT SKYBLUE (-7000 3600);
FORCEPROP 1 LAST MATERIAL CHIP
J 0
(-7000 3550);
DISPLAY 0.489362 (-7000 3550);
PAINT SKYBLUE (-7000 3550);
FORCEPROP 1 LAST PART_NUMBER CS04992FB31
J 0
(-7000 3500);
DISPLAY 0.489362 (-7000 3500);
PAINT SKYBLUE (-7000 3500);
FORCEPROP 1 LAST VALUE 49.9
J 0
(-7000 3700);
DISPLAY 0.489362 (-7000 3700);
PAINT SKYBLUE (-7000 3700);
FORCEPROP 1 LAST TOLERANCE 1%
J 0
(-7000 3650);
DISPLAY 0.489362 (-7000 3650);
PAINT SKYBLUE (-7000 3650);
FORCEPROP 2 LAST CDS_LIB pure_quanta
J 0
(-7050 3625);
DISPLAY INVISIBLE (-7050 3625);
FORCEPROP 1 LAST PATH I82
J 0
(-7000 3800);
DISPLAY 0.978723 (-7000 3800);
PAINT WHITE (-7000 3800);
DISPLAY INVISIBLE (-7000 3800);
FORCEADD UNIVERSAL_GND..1
(-7050 3425);
FORCEPROP 3 LASTPIN (-7050 3475) SIG_NAME GND\g
J 0
(-7040 3485);
DISPLAY 0.659574 (-7040 3485);
PAINT MONO (-7040 3485);
DISPLAY INVISIBLE (-7040 3485);
FORCEPROP 2 LAST CDS_LIB pure_quanta_power
J 0
(-7050 3425);
DISPLAY INVISIBLE (-7050 3425);
FORCEPROP 1 LAST PATH I83
J 0
(-6975 3425);
DISPLAY 0.872340 (-6975 3425);
PAINT AQUA (-6975 3425);
DISPLAY INVISIBLE (-6975 3425);
FORCEPROP 1 LAST HDL_POWER GND
J 1
(-7025 3350);
DISPLAY 0.872340 (-7025 3350);
PAINT GREEN (-7025 3350);
DISPLAY INVISIBLE (-7025 3350);
FORCEADD VCC_CORE..1
(-7050 4450);
FORCEPROP 3 LASTPIN (-7050 4400) SIG_NAME PVDDCR_CPU0_P0\g
J 0
(-7040 4410);
DISPLAY 0.659574 (-7040 4410);
PAINT MONO (-7040 4410);
DISPLAY INVISIBLE (-7040 4410);
FORCEPROP 1 LAST HDL_POWER PVDDCR_CPU0_P0
J 1
(-7050 4500);
DISPLAY 0.489362 (-7050 4500);
PAINT GREEN (-7050 4500);
FORCEPROP 2 LAST CDS_LIB pure_quanta_power
J 0
(-7050 4450);
DISPLAY INVISIBLE (-7050 4450);
FORCEPROP 1 LAST PATH I84
J 0
(-7000 4475);
DISPLAY 0.872340 (-7000 4475);
PAINT AQUA (-7000 4475);
DISPLAY INVISIBLE (-7000 4475);
FORCEADD VCC_CORE..1
(-7050 3300);
FORCEPROP 3 LASTPIN (-7050 3250) SIG_NAME PVDDCR_SOC_P0\g
J 0
(-7040 3260);
DISPLAY 0.659574 (-7040 3260);
PAINT MONO (-7040 3260);
DISPLAY INVISIBLE (-7040 3260);
FORCEPROP 1 LAST HDL_POWER PVDDCR_SOC_P0
J 1
(-7050 3350);
DISPLAY 0.489362 (-7050 3350);
PAINT GREEN (-7050 3350);
FORCEPROP 2 LAST CDS_LIB pure_quanta_power
J 0
(-7050 3300);
DISPLAY INVISIBLE (-7050 3300);
FORCEPROP 1 LAST PATH I85
J 0
(-7000 3325);
DISPLAY 0.872340 (-7000 3325);
PAINT AQUA (-7000 3325);
DISPLAY INVISIBLE (-7000 3325);
FORCEADD Q_RES..2
(-7050 3125);
FORCEPROP 1 LAST LOCATION PR296
J 0
(-7000 3250);
DISPLAY 0.489362 (-7000 3250);
PAINT SKYBLUE (-7000 3250);
FORCEPROP 0 LAST $SEC 1
J 0
(-7000 3300);
DISPLAY 0.680851 (-7000 3300);
PAINT MONO (-7000 3300);
DISPLAY INVISIBLE (-7000 3300);
FORCEPROP 0 LAST CDS_SEC 1
J 0
(-7000 3300);
DISPLAY 1.021277 (-7000 3300);
DISPLAY INVISIBLE (-7000 3300);
FORCEPROP 1 LASTPIN (-7050 3225) $PN 1
J 0
(-7045 3187);
DISPLAY 0.489362 (-7045 3187);
PAINT MONO (-7045 3187);
FORCEPROP 1 LASTPIN (-7050 3025) $PN 2
J 0
(-7045 3035);
DISPLAY 0.489362 (-7045 3035);
PAINT MONO (-7045 3035);
FORCEPROP 1 LAST WATTAGE 1/16W
J 0
(-7000 3100);
DISPLAY 0.489362 (-7000 3100);
PAINT SKYBLUE (-7000 3100);
FORCEPROP 1 LAST MATERIAL CHIP
J 0
(-7000 3050);
DISPLAY 0.489362 (-7000 3050);
PAINT SKYBLUE (-7000 3050);
FORCEPROP 1 LAST PART_NUMBER CS04992FB31
J 0
(-7000 3000);
DISPLAY 0.489362 (-7000 3000);
PAINT SKYBLUE (-7000 3000);
FORCEPROP 1 LAST PACK_TYPE 0402LF
J 0
(-7000 2950);
DISPLAY 0.489362 (-7000 2950);
PAINT SKYBLUE (-7000 2950);
FORCEPROP 1 LAST VALUE 49.9
J 0
(-7000 3200);
DISPLAY 0.489362 (-7000 3200);
PAINT SKYBLUE (-7000 3200);
FORCEPROP 1 LAST TOLERANCE 1%
J 0
(-7000 3150);
DISPLAY 0.489362 (-7000 3150);
PAINT SKYBLUE (-7000 3150);
FORCEPROP 2 LAST CDS_LIB pure_quanta
J 0
(-7050 3125);
DISPLAY INVISIBLE (-7050 3125);
FORCEPROP 1 LAST PATH I86
J 0
(-7000 3300);
DISPLAY 0.978723 (-7000 3300);
PAINT WHITE (-7000 3300);
DISPLAY INVISIBLE (-7000 3300);
FORCEADD Q_CAP..1
(-5675 2825);
FORCEPROP 1 LAST LOCATION PC464
J 0
(-5625 2875);
DISPLAY 0.489362 (-5625 2875);
PAINT SKYBLUE (-5625 2875);
FORCEPROP 0 LAST $SEC 1
J 0
(-5625 2975);
DISPLAY 0.680851 (-5625 2975);
PAINT MONO (-5625 2975);
DISPLAY INVISIBLE (-5625 2975);
FORCEPROP 0 LAST CDS_SEC 1
J 0
(-5625 2975);
DISPLAY 1.021277 (-5625 2975);
DISPLAY INVISIBLE (-5625 2975);
FORCEPROP 1 LASTPIN (-5675 2925) $PN 1
J 0
(-5665 2905);
DISPLAY 0.489362 (-5665 2905);
PAINT MONO (-5665 2905);
FORCEPROP 1 LASTPIN (-5675 2725) $PN 2
J 0
(-5665 2705);
DISPLAY 0.489362 (-5665 2705);
PAINT MONO (-5665 2705);
FORCEPROP 1 LAST MATERIAL X7R
J 0
(-5625 2775);
DISPLAY 0.489362 (-5625 2775);
PAINT SKYBLUE (-5625 2775);
FORCEPROP 1 LAST TOLERANCE 10%
J 0
(-5625 2800);
DISPLAY 0.489362 (-5625 2800);
PAINT SKYBLUE (-5625 2800);
FORCEPROP 1 LAST VALUE 3300PF
J 0
(-5625 2850);
DISPLAY 0.489362 (-5625 2850);
PAINT SKYBLUE (-5625 2850);
FORCEPROP 1 LAST PART_NUMBER TMP_QCH2336K1B12
J 0
(-5625 2750);
DISPLAY 0.489362 (-5625 2750);
PAINT SKYBLUE (-5625 2750);
FORCEPROP 1 LAST VOLTAGE 50V
J 0
(-5625 2825);
DISPLAY 0.489362 (-5625 2825);
PAINT SKYBLUE (-5625 2825);
FORCEPROP 1 LAST PACK_TYPE 0402
J 0
(-5625 2725);
DISPLAY 0.489362 (-5625 2725);
PAINT SKYBLUE (-5625 2725);
FORCEPROP 2 LAST CDS_LIB pure_quanta
J 0
(-5675 2825);
DISPLAY INVISIBLE (-5675 2825);
FORCEPROP 1 LAST PATH I87
J 0
(-5625 2975);
DISPLAY 0.978723 (-5625 2975);
PAINT WHITE (-5625 2975);
DISPLAY INVISIBLE (-5625 2975);
FORCEADD Q_RES..1
(-5950 2950);
FORCEPROP 1 LAST LOCATION PR307
J 0
(-6000 3000);
DISPLAY 0.489362 (-6000 3000);
PAINT SKYBLUE (-6000 3000);
FORCEPROP 0 LAST $SEC 1
J 0
(-6000 3050);
DISPLAY 0.680851 (-6000 3050);
PAINT MONO (-6000 3050);
DISPLAY INVISIBLE (-6000 3050);
FORCEPROP 0 LAST CDS_SEC 1
J 0
(-6000 3050);
DISPLAY 1.021277 (-6000 3050);
DISPLAY INVISIBLE (-6000 3050);
FORCEPROP 1 LASTPIN (-6050 2950) $PN 1
J 0
(-6038 2962);
DISPLAY 0.489362 (-6038 2962);
PAINT MONO (-6038 2962);
FORCEPROP 1 LASTPIN (-5850 2950) $PN 2
J 0
(-5888 2962);
DISPLAY 0.489362 (-5888 2962);
PAINT MONO (-5888 2962);
FORCEPROP 1 LAST WATTAGE 1/16W
J 0
(-5850 2900);
DISPLAY 0.489362 (-5850 2900);
PAINT SKYBLUE (-5850 2900);
FORCEPROP 1 LAST MATERIAL CHIP
J 0
(-6275 2875);
DISPLAY 0.489362 (-6275 2875);
PAINT SKYBLUE (-6275 2875);
FORCEPROP 1 LAST TOLERANCE 1%
J 0
(-5825 2975);
DISPLAY 0.489362 (-5825 2975);
PAINT SKYBLUE (-5825 2975);
FORCEPROP 1 LAST VALUE 10
J 2
(-6075 2975);
DISPLAY 0.489362 (-6075 2975);
PAINT SKYBLUE (-6075 2975);
FORCEPROP 1 LAST PART_NUMBER TMP_QCS01002FB21
J 0
(-6275 2900);
DISPLAY 0.489362 (-6275 2900);
PAINT SKYBLUE (-6275 2900);
FORCEPROP 1 LAST PACK_TYPE 0402LF
J 0
(-5850 2875);
DISPLAY 0.489362 (-5850 2875);
PAINT SKYBLUE (-5850 2875);
FORCEPROP 2 LAST CDS_LIB pure_quanta
J 0
(-5950 2950);
DISPLAY INVISIBLE (-5950 2950);
FORCEPROP 1 LAST PATH I88
J 0
(-6000 3100);
DISPLAY 0.978723 (-6000 3100);
PAINT WHITE (-6000 3100);
DISPLAY INVISIBLE (-6000 3100);
FORCEADD Q_RES..2
(-7050 2525);
FORCEPROP 1 LAST LOCATION PR297
J 0
(-7000 2650);
DISPLAY 0.489362 (-7000 2650);
PAINT SKYBLUE (-7000 2650);
FORCEPROP 0 LAST $SEC 1
J 0
(-7000 2700);
DISPLAY 0.680851 (-7000 2700);
PAINT MONO (-7000 2700);
DISPLAY INVISIBLE (-7000 2700);
FORCEPROP 0 LAST CDS_SEC 1
J 0
(-7000 2700);
DISPLAY 1.021277 (-7000 2700);
DISPLAY INVISIBLE (-7000 2700);
FORCEPROP 1 LASTPIN (-7050 2625) $PN 1
J 0
(-7045 2587);
DISPLAY 0.489362 (-7045 2587);
PAINT MONO (-7045 2587);
FORCEPROP 1 LASTPIN (-7050 2425) $PN 2
J 0
(-7045 2435);
DISPLAY 0.489362 (-7045 2435);
PAINT MONO (-7045 2435);
FORCEPROP 1 LAST WATTAGE 1/16W
J 0
(-7000 2500);
DISPLAY 0.489362 (-7000 2500);
PAINT SKYBLUE (-7000 2500);
FORCEPROP 1 LAST MATERIAL CHIP
J 0
(-7000 2450);
DISPLAY 0.489362 (-7000 2450);
PAINT SKYBLUE (-7000 2450);
FORCEPROP 1 LAST PART_NUMBER CS04992FB31
J 0
(-7000 2400);
DISPLAY 0.489362 (-7000 2400);
PAINT SKYBLUE (-7000 2400);
FORCEPROP 1 LAST PACK_TYPE 0402LF
J 0
(-7000 2350);
DISPLAY 0.489362 (-7000 2350);
PAINT SKYBLUE (-7000 2350);
FORCEPROP 1 LAST VALUE 49.9
J 0
(-7000 2600);
DISPLAY 0.489362 (-7000 2600);
PAINT SKYBLUE (-7000 2600);
FORCEPROP 1 LAST TOLERANCE 1%
J 0
(-7000 2550);
DISPLAY 0.489362 (-7000 2550);
PAINT SKYBLUE (-7000 2550);
FORCEPROP 2 LAST CDS_LIB pure_quanta
J 0
(-7050 2525);
DISPLAY INVISIBLE (-7050 2525);
FORCEPROP 1 LAST PATH I90
J 0
(-7000 2700);
DISPLAY 0.978723 (-7000 2700);
PAINT WHITE (-7000 2700);
DISPLAY INVISIBLE (-7000 2700);
FORCEADD UNIVERSAL_GND..1
(-7050 2325);
FORCEPROP 3 LASTPIN (-7050 2375) SIG_NAME GND\g
J 0
(-7040 2385);
DISPLAY 0.659574 (-7040 2385);
PAINT MONO (-7040 2385);
DISPLAY INVISIBLE (-7040 2385);
FORCEPROP 2 LAST CDS_LIB pure_quanta_power
J 0
(-7050 2325);
DISPLAY INVISIBLE (-7050 2325);
FORCEPROP 1 LAST PATH I91
J 0
(-6975 2325);
DISPLAY 0.872340 (-6975 2325);
PAINT AQUA (-6975 2325);
DISPLAY INVISIBLE (-6975 2325);
FORCEPROP 1 LAST HDL_POWER GND
J 1
(-7025 2250);
DISPLAY 0.872340 (-7025 2250);
PAINT GREEN (-7025 2250);
DISPLAY INVISIBLE (-7025 2250);
FORCEADD OFFPAGE..4
R 2
(-7800 2950);
FORCEPROP 2 LAST $XR0 27 
J 0
(-8081 2950);
DISPLAY 0.638298 (-8081 2950);
PAINT MONO (-8081 2950);
FORCEPROP 2 LAST CDS_LIB standard
J 0
(-7800 2950);
DISPLAY INVISIBLE (-7800 2950);
FORCEPROP 1 LAST OFFPAGE TRUE
J 2
(-8125 2825);
DISPLAY 0.872340 (-8125 2825);
PAINT GREEN (-8125 2825);
DISPLAY INVISIBLE (-8125 2825);
FORCEPROP 1 LAST COMMENT_BODY TRUE
J 2
(-7775 2850);
DISPLAY 0.872340 (-7775 2850);
PAINT GREEN (-7775 2850);
DISPLAY INVISIBLE (-7775 2850);
FORCEPROP 2 LAST PATH I92
J 0
(-7750 3025);
DISPLAY 1.021277 (-7750 3025);
DISPLAY INVISIBLE (-7750 3025);
FORCEADD OFFPAGE..4
R 2
(-7800 2700);
FORCEPROP 2 LAST $XR1 169 
J 0
(-8201 2700);
DISPLAY 0.638298 (-8201 2700);
PAINT MONO (-8201 2700);
FORCEPROP 2 LAST $XR0 27 
J 0
(-8081 2700);
DISPLAY 0.638298 (-8081 2700);
PAINT MONO (-8081 2700);
FORCEPROP 2 LAST CDS_LIB standard
J 0
(-7800 2700);
DISPLAY INVISIBLE (-7800 2700);
FORCEPROP 1 LAST OFFPAGE TRUE
J 2
(-8125 2575);
DISPLAY 0.872340 (-8125 2575);
PAINT GREEN (-8125 2575);
DISPLAY INVISIBLE (-8125 2575);
FORCEPROP 1 LAST COMMENT_BODY TRUE
J 2
(-7775 2600);
DISPLAY 0.872340 (-7775 2600);
PAINT GREEN (-7775 2600);
DISPLAY INVISIBLE (-7775 2600);
FORCEPROP 2 LAST PATH I93
J 0
(-7750 2775);
DISPLAY 1.021277 (-7750 2775);
DISPLAY INVISIBLE (-7750 2775);
FORCEADD UNIVERSAL_GND..1
(-5100 450);
FORCEPROP 3 LASTPIN (-5100 500) SIG_NAME GND\g
J 0
(-5090 510);
DISPLAY 0.659574 (-5090 510);
PAINT MONO (-5090 510);
DISPLAY INVISIBLE (-5090 510);
FORCEPROP 2 LAST CDS_LIB pure_quanta_power
J 0
(-5100 450);
DISPLAY INVISIBLE (-5100 450);
FORCEPROP 1 LAST PATH I99
J 0
(-5025 450);
DISPLAY 0.872340 (-5025 450);
PAINT AQUA (-5025 450);
DISPLAY INVISIBLE (-5025 450);
FORCEPROP 1 LAST HDL_POWER GND
J 1
(-5075 375);
DISPLAY 0.872340 (-5075 375);
PAINT GREEN (-5075 375);
DISPLAY INVISIBLE (-5075 375);
FORCEADD DNS..1
(-8325 5950);
PAINT RED (-8325 5950);
FORCEPROP 2 LAST CDS_LIB mstr_misc
J 0
(-8325 5950);
DISPLAY INVISIBLE (-8325 5950);
FORCEPROP 1 LAST COMMENT_BODY TRUE
R 1
J 0
(-8250 5725);
DISPLAY 0.872340 (-8250 5725);
PAINT GREEN (-8250 5725);
DISPLAY INVISIBLE (-8250 5725);
FORCEADD DNS..1
(-8025 5000);
PAINT RED (-8025 5000);
FORCEPROP 2 LAST CDS_LIB mstr_misc
J 0
(-8025 5000);
DISPLAY INVISIBLE (-8025 5000);
FORCEPROP 1 LAST COMMENT_BODY TRUE
R 1
J 0
(-7950 4775);
DISPLAY 0.872340 (-7950 4775);
PAINT GREEN (-7950 4775);
DISPLAY INVISIBLE (-7950 4775);
FORCEADD DNS..1
(-5650 450);
PAINT RED (-5650 450);
FORCEPROP 2 LAST CDS_LIB mstr_misc
J 0
(-5650 450);
DISPLAY INVISIBLE (-5650 450);
FORCEPROP 1 LAST COMMENT_BODY TRUE
R 1
J 0
(-5575 225);
DISPLAY 0.872340 (-5575 225);
PAINT GREEN (-5575 225);
DISPLAY INVISIBLE (-5575 225);
FORCEADD DNS..1
(-7600 5000);
PAINT RED (-7600 5000);
FORCEPROP 2 LAST CDS_LIB mstr_misc
J 0
(-7600 5000);
DISPLAY INVISIBLE (-7600 5000);
FORCEPROP 1 LAST COMMENT_BODY TRUE
R 1
J 0
(-7525 4775);
DISPLAY 0.872340 (-7525 4775);
PAINT GREEN (-7525 4775);
DISPLAY INVISIBLE (-7525 4775);
FORCEADD DNS..1
(-8250 5000);
PAINT RED (-8250 5000);
FORCEPROP 2 LAST CDS_LIB mstr_misc
J 0
(-8250 5000);
DISPLAY INVISIBLE (-8250 5000);
FORCEPROP 1 LAST COMMENT_BODY TRUE
R 1
J 0
(-8175 4775);
DISPLAY 0.872340 (-8175 4775);
PAINT GREEN (-8175 4775);
DISPLAY INVISIBLE (-8175 4775);
FORCEADD DNS..1
(-7675 5950);
PAINT RED (-7675 5950);
FORCEPROP 2 LAST CDS_LIB mstr_misc
J 0
(-7675 5950);
DISPLAY INVISIBLE (-7675 5950);
FORCEPROP 1 LAST COMMENT_BODY TRUE
R 1
J 0
(-7600 5725);
DISPLAY 0.872340 (-7600 5725);
PAINT GREEN (-7600 5725);
DISPLAY INVISIBLE (-7600 5725);
FORCEADD DNS..1
(-5650 1225);
PAINT RED (-5650 1225);
FORCEPROP 2 LAST CDS_LIB mstr_misc
J 0
(-5650 1225);
DISPLAY INVISIBLE (-5650 1225);
FORCEPROP 1 LAST COMMENT_BODY TRUE
R 1
J 0
(-5575 1000);
DISPLAY 0.872340 (-5575 1000);
PAINT GREEN (-5575 1000);
DISPLAY INVISIBLE (-5575 1000);
FORCEADD QUANTA_TITLE_BLOCK_C..1
(0 0);
FORCEPROP 0 LAST CDS_CON_LAST_MODIFIED Fri Mar 11 14:53:23 2022
J 0
(-1885 15);
DISPLAY INVISIBLE (-1885 15);
FORCEPROP 1 LAST CUSTOM_TXT_CDS <CON_LAST_MODIFIED>
J 0
(-1885 15);
DISPLAY 0.978723 (-1885 15);
FORCEPROP 2 LAST CUSTOM_TXT_CDS <XR_PAGE_TITLE>
J 0
(-7890 5250);
DISPLAY 0.638298 (-7890 5250);
PAINT PINK (-7890 5250);
DISPLAY INVISIBLE (-7890 5250);
FORCEPROP 1 LAST CUSTOM_TXT_CDS <NAME_2>
J 0
(-3175 50);
FORCEPROP 1 LAST CUSTOM_TXT_CDS <NAME_1>
J 0
(-3175 175);
FORCEPROP 1 LAST CUSTOM_TXT_CDS <Q_NUMBER>
J 0
(-1403 103);
DISPLAY 1.212766 (-1403 103);
FORCEPROP 1 LAST CUSTOM_TXT_CDS <Q_PROJ>
J 0
(-2382 102);
DISPLAY 1.212766 (-2382 102);
FORCEPROP 1 LAST CUSTOM_TXT_CDS <Q_REV>
J 0
(-184 103);
DISPLAY 1.212766 (-184 103);
FORCEPROP 1 LAST CUSTOM_TXT_CDS <CON_PAGE_NUM> OF <CON_TOTAL_PAGES>
J 0
(-446 18);
DISPLAY 0.978723 (-446 18);
FORCEPROP 1 LAST Q_DEPT BU9
J 1
(-3763 49);
DISPLAY 1.957447 (-3763 49);
PAINT GREEN (-3763 49);
FORCEPROP 1 LAST Q_TITLE PVDDCR_CPU0_P0/PVDDCR_SOC_P0 VR CONTROLLER
J 0
(-9366 26);
DISPLAY 2.446809 (-9366 26);
PAINT GREEN (-9366 26);
FORCEPROP 2 LAST PAGE_BORDER TRUE
J 0
(-7890 5250);
DISPLAY 0.638298 (-7890 5250);
PAINT PINK (-7890 5250);
DISPLAY INVISIBLE (-7890 5250);
FORCEPROP 1 LAST CDS_LMAN_SYM_OUTLINE -9475,6775,100,-125
J 0
(0 0);
DISPLAY 0.468085 (0 0);
PAINT GREEN (0 0);
DISPLAY INVISIBLE (0 0);
FORCEPROP 2 LAST CDS_LIB pure_quanta
J 0
(0 0);
DISPLAY INVISIBLE (0 0);
FORCEPROP 1 LAST COMMENT_BODY TRUE
J 0
(12 -13);
DISPLAY 0.978723 (12 -13);
PAINT GREEN (12 -13);
DISPLAY INVISIBLE (12 -13);
FORCEPROP 2 LAST CDS_XR_PAGE_TITLE CR-169 : @T6G_MB_LIB.T6G(SCH_1):PAGE169
J 0
(-7890 5250);
DISPLAY 0.638298 (-7890 5250);
PAINT PINK (-7890 5250);
DISPLAY INVISIBLE (-7890 5250);
FORCEADD DNS..1
(-7825 5000);
PAINT RED (-7825 5000);
FORCEPROP 2 LAST CDS_LIB mstr_misc
J 0
(-7825 5000);
DISPLAY INVISIBLE (-7825 5000);
FORCEPROP 1 LAST COMMENT_BODY TRUE
R 1
J 0
(-7750 4775);
DISPLAY 0.872340 (-7750 4775);
PAINT GREEN (-7750 4775);
DISPLAY INVISIBLE (-7750 4775);
FORCEADD DNS..1
(-7975 5950);
PAINT RED (-7975 5950);
FORCEPROP 2 LAST CDS_LIB mstr_misc
J 0
(-7975 5950);
DISPLAY INVISIBLE (-7975 5950);
FORCEPROP 1 LAST COMMENT_BODY TRUE
R 1
J 0
(-7900 5725);
DISPLAY 0.872340 (-7900 5725);
PAINT GREEN (-7900 5725);
DISPLAY INVISIBLE (-7900 5725);
FORCEADD DNS..1
(-5250 6350);
PAINT RED (-5250 6350);
FORCEPROP 2 LAST CDS_LIB mstr_misc
J 0
(-5250 6350);
DISPLAY INVISIBLE (-5250 6350);
FORCEPROP 1 LAST COMMENT_BODY TRUE
R 1
J 0
(-5175 6125);
DISPLAY 0.872340 (-5175 6125);
PAINT GREEN (-5175 6125);
DISPLAY INVISIBLE (-5175 6125);
FORCEADD DNS..1
(-7400 5950);
PAINT RED (-7400 5950);
FORCEPROP 2 LAST CDS_LIB mstr_misc
J 0
(-7400 5950);
DISPLAY INVISIBLE (-7400 5950);
FORCEPROP 1 LAST COMMENT_BODY TRUE
R 1
J 0
(-7325 5725);
DISPLAY 0.872340 (-7325 5725);
PAINT GREEN (-7325 5725);
DISPLAY INVISIBLE (-7325 5725);
WIRE 16 -1 (-2900 5925)(-2900 6025);
WIRE 16 -1 (-5300 375)(-5300 300);
WIRE 16 -1 (-6950 525)(-6950 450);
WIRE 16 -1 (-6475 525)(-6475 450);
WIRE 16 -1 (-2925 5475)(-2925 5550);
WIRE 16 -1 (-8175 1100)(-8175 1050);
WIRE 16 -1 (-7825 4925)(-7825 4825);
WIRE 16 -1 (-7600 4925)(-7600 4825);
WIRE 16 -1 (-3200 6025)(-3200 5925);
WIRE 16 -1 (-3200 5550)(-3200 5475);
WIRE 16 -1 (-5575 1725)(-5325 1725);
WIRE 16 -1 (-8050 4925)(-8050 4825);
WIRE 16 -1 (-5675 350)(-5675 300);
WIRE 16 -1 (-3375 600)(-3375 475);
WIRE 16 -1 (-2750 825)(-2750 925);
WIRE 16 -1 (-8525 4925)(-8525 4825);
WIRE 16 -1 (-8275 4825)(-8275 4925);
WIRE 16 -1 (-7050 3525)(-7050 3475);
WIRE 16 -1 (-7050 4350)(-7050 4400);
WIRE 16 -1 (-7050 3225)(-7050 3250);
WIRE 16 -1 (-7050 2425)(-7050 2375);
WIRE 16 -1 (-5675 2725)(-5675 2700);
WIRE 16 -1 (-5675 2700)(-5025 2700);
WIRE 16 -1 (-5675 2700)(-7050 2700);
WIRE 16 -1 (-7750 2700)(-7050 2700);
FORCEPROP 2 LAST SIG_NAME VSENSE_VSS_SENSE_A_P0
J 2
(-7260 2710);
DISPLAY 0.489362 (-7260 2710);
WIRE 16 -1 (-7050 2625)(-7050 2700);
WIRE 16 -1 (-7750 2950)(-7050 2950);
FORCEPROP 2 LAST SIG_NAME VSENSE_PVDDCR_SOC_P0_DP
J 2
(-7210 2960);
DISPLAY 0.489362 (-7210 2960);
WIRE 16 -1 (-6050 2950)(-7050 2950);
WIRE 16 -1 (-7050 3025)(-7050 2950);
WIRE 16 -1 (-5750 3825)(-5750 3800);
WIRE 16 -1 (-5025 3800)(-5750 3800);
WIRE 16 -1 (-5750 3800)(-7050 3800);
WIRE 16 -1 (-7750 3800)(-7050 3800);
FORCEPROP 2 LAST SIG_NAME VSENSE_VSS_SENSE_A_P0
J 2
(-7260 3810);
DISPLAY 0.489362 (-7260 3810);
WIRE 16 -1 (-7050 3725)(-7050 3800);
WIRE 16 -1 (-7750 4050)(-7050 4050);
FORCEPROP 2 LAST SIG_NAME VSENSE_PVDDCR_CPU0_P0_DP
J 2
(-7185 4060);
DISPLAY 0.489362 (-7185 4060);
WIRE 16 -1 (-7050 4150)(-7050 4050);
WIRE 16 -1 (-6125 4050)(-7050 4050);
WIRE 17 273 (-1675 6575)(-1675 5275);
WIRE 17 273 (-1675 6575)(-75 6575);
WIRE 17 273 (-1675 5275)(-75 5275);
WIRE 17 273 (-75 6575)(-75 5275);
WIRE 17 273 (-1675 5200)(-1675 4025);
WIRE 17 273 (-1675 5200)(-75 5200);
WIRE 17 273 (-1675 4025)(-75 4025);
WIRE 17 273 (-75 5200)(-75 4025);
WIRE 17 273 (-9175 600)(-7975 600);
WIRE 17 273 (-9175 600)(-9175 225);
WIRE 17 273 (-7975 600)(-7975 225);
WIRE 17 273 (-9175 225)(-7975 225);
WIRE 16 -1 (-3675 2400)(-2850 2400);
FORCEPROP 2 LAST SIG_NAME PVDDCR_SOC_P0_PWM3
J 2
(-3075 2410);
DISPLAY 0.489362 (-3075 2410);
WIRE 16 -1 (-5825 1350)(-5025 1350);
FORCEPROP 2 LAST SIG_NAME PVDDCR_SOC_P0_EN//ADDR_CFG
J 2
(-5135 1360);
DISPLAY 0.489362 (-5135 1360);
FORCEPROP 2 LASTPROP $XRERR UNIQUE?
J 0
(-5375 1360);
DISPLAY 0.638298 (-5375 1360);
PAINT MONO (-5375 1360);
DISPLAY INVISIBLE (-5375 1360);
WIRE 16 -1 (-5825 1500)(-5825 1350);
WIRE 16 -1 (-7100 1500)(-5825 1500);
WIRE 16 -1 (-7100 1550)(-7100 1500);
WIRE 16 -1 (-7100 1500)(-7100 1475);
WIRE 16 -1 (-3675 3200)(-3025 3200);
FORCEPROP 2 LAST SIG_NAME NC_PVDDCR_CPU0_P0_IMON7
J 2
(-3060 3210);
DISPLAY 0.489362 (-3060 3210);
FORCEPROP 2 LASTPROP $XRERR UNIQUE?
J 0
(-3300 3210);
DISPLAY 0.638298 (-3300 3210);
PAINT MONO (-3300 3210);
DISPLAY INVISIBLE (-3300 3210);
WIRE 16 -1 (-3675 3500)(-2850 3500);
FORCEPROP 2 LAST SIG_NAME PVDDCR_CPU0_P0_IMON6
J 2
(-3060 3510);
DISPLAY 0.489362 (-3060 3510);
WIRE 16 -1 (-3675 3600)(-2850 3600);
FORCEPROP 2 LAST SIG_NAME PVDDCR_CPU0_P0_PWM6
J 2
(-3085 3610);
DISPLAY 0.489362 (-3085 3610);
WIRE 16 -1 (-6225 1250)(-6050 1250);
WIRE 16 -1 (-6050 1250)(-5750 1250);
WIRE 16 -1 (-6050 1250)(-6050 1000);
WIRE 16 -1 (-6050 1000)(-5325 1000);
FORCEPROP 2 LAST SIG_NAME PWRGD_PVDDCR_SOC_P0_R
J 2
(-5485 1010);
DISPLAY 0.489362 (-5485 1010);
FORCEPROP 2 LASTPROP $XRERR UNIQUE?
J 0
(-5725 1010);
DISPLAY 0.638298 (-5725 1010);
PAINT MONO (-5725 1010);
DISPLAY INVISIBLE (-5725 1010);
WIRE 16 -1 (-6050 1000)(-6225 1000);
WIRE 16 -1 (-5325 850)(-5325 1000);
WIRE 16 -1 (-5025 850)(-5325 850);
WIRE 16 -1 (-5300 575)(-5300 650);
WIRE 16 -1 (-5025 650)(-5300 650);
FORCEPROP 2 LAST SIG_NAME PVDDCR_CPU0_P0_VINSEN
J 2
(-5135 660);
DISPLAY 0.489362 (-5135 660);
FORCEPROP 2 LASTPROP $XRERR UNIQUE?
J 0
(-5375 660);
DISPLAY 0.638298 (-5375 660);
PAINT MONO (-5375 660);
DISPLAY INVISIBLE (-5375 660);
WIRE 16 -1 (-5675 650)(-5300 650);
WIRE 16 -1 (-5675 550)(-5675 650);
WIRE 16 -1 (-5875 650)(-5675 650);
WIRE 16 -1 (-3675 2300)(-2850 2300);
FORCEPROP 2 LAST SIG_NAME PVDDCR_SOC_P0_IMON3
J 2
(-3075 2310);
DISPLAY 0.489362 (-3075 2310);
WIRE 16 -1 (-3675 2600)(-3025 2600);
FORCEPROP 2 LAST SIG_NAME NC_PVDDCR_CPU0_P0_IMON9
J 2
(-3060 2610);
DISPLAY 0.489362 (-3060 2610);
FORCEPROP 2 LASTPROP $XRERR UNIQUE?
J 0
(-3300 2610);
DISPLAY 0.638298 (-3300 2610);
PAINT MONO (-3300 2610);
DISPLAY INVISIBLE (-3300 2610);
WIRE 16 -1 (-3675 2700)(-2850 2700);
FORCEPROP 2 LAST SIG_NAME NC_PVDDCR_CPU0_P0_PWM9
J 2
(-3060 2710);
DISPLAY 0.489362 (-3060 2710);
FORCEPROP 2 LASTPROP $XRERR UNIQUE?
J 0
(-2820 2700);
DISPLAY 0.638298 (-2820 2700);
PAINT MONO (-2820 2700);
DISPLAY INVISIBLE (-2820 2700);
WIRE 16 -1 (-5625 6375)(-5625 6100);
WIRE 16 -1 (-5625 6375)(-5350 6375);
WIRE 16 -1 (-6025 6375)(-5625 6375);
WIRE 16 -1 (-5625 6100)(-5025 6100);
FORCEPROP 2 LAST SIG_NAME PWRGD_PVDDCR_CPU0_P0_R
J 2
(-5110 6110);
DISPLAY 0.489362 (-5110 6110);
FORCEPROP 2 LASTPROP $XRERR UNIQUE?
J 0
(-5350 6110);
DISPLAY 0.638298 (-5350 6110);
PAINT MONO (-5350 6110);
DISPLAY INVISIBLE (-5350 6110);
WIRE 16 -1 (-5625 6100)(-5800 6100);
WIRE 16 -1 (-5750 4025)(-5750 4050);
WIRE 16 -1 (-5025 4050)(-5750 4050);
FORCEPROP 2 LAST SIG_NAME VSENSE_PVDDCR_CPU0_P0_VSEN0
J 2
(-5135 4060);
DISPLAY 0.489362 (-5135 4060);
FORCEPROP 2 LASTPROP $XRERR UNIQUE?
J 0
(-5375 4060);
DISPLAY 0.638298 (-5375 4060);
PAINT MONO (-5375 4060);
DISPLAY INVISIBLE (-5375 4060);
WIRE 16 -1 (-5925 4050)(-5750 4050);
WIRE 17 273 (-8000 4275)(-8000 3465);
WIRE 17 273 (-8000 4275)(-7150 4275);
WIRE 17 273 (-8000 3465)(-7150 3465);
WIRE 17 273 (-7150 4275)(-7150 3465);
WIRE 16 -1 (-3675 1700)(-2850 1700);
FORCEPROP 2 LAST SIG_NAME PVDDCR_SOC_P0_IMON1
J 2
(-3075 1710);
DISPLAY 0.489362 (-3075 1710);
WIRE 16 -1 (-2750 1200)(-2525 1200);
WIRE 16 -1 (-2750 1125)(-2750 1200);
WIRE 16 -1 (-2750 1200)(-3675 1200);
FORCEPROP 2 LAST SIG_NAME PVDDCR_SOC_P0_TEMP1
J 2
(-3035 1210);
DISPLAY 0.489362 (-3035 1210);
WIRE 16 -1 (-7400 5650)(-7600 5650);
WIRE 16 -1 (-7400 5650)(-5025 5650);
FORCEPROP 2 LAST SIG_NAME SVID_PVDDCR_CPU0_P0_SVC_R
J 0
(-5710 5660);
DISPLAY 0.489362 (-5710 5660);
WIRE 16 -1 (-7400 5875)(-7400 5650);
WIRE 16 -1 (-7600 5125)(-7600 5650);
WIRE 16 -1 (-7600 5650)(-8800 5650);
WIRE 16 -1 (-5800 5950)(-5625 5950);
WIRE 16 -1 (-5625 5950)(-5025 5950);
FORCEPROP 2 LAST SIG_NAME PVDDCR_CPU0_P0_EN_R
J 2
(-5135 5960);
DISPLAY 0.489362 (-5135 5960);
FORCEPROP 2 LASTPROP $XRERR UNIQUE?
J 0
(-5375 5960);
DISPLAY 0.638298 (-5375 5960);
PAINT MONO (-5375 5960);
DISPLAY INVISIBLE (-5375 5960);
WIRE 16 -1 (-5625 5825)(-5625 5950);
WIRE 16 -1 (-5325 5825)(-5625 5825);
WIRE 16 -1 (-7675 5875)(-7675 5500);
WIRE 16 -1 (-5025 5500)(-7675 5500);
FORCEPROP 2 LAST SIG_NAME SVID_PVDDCR_CPU0_P0_SVD_R
J 0
(-5710 5510);
DISPLAY 0.489362 (-5710 5510);
WIRE 16 -1 (-7675 5500)(-7825 5500);
WIRE 16 -1 (-7825 5125)(-7825 5500);
WIRE 16 -1 (-8800 5500)(-7825 5500);
WIRE 16 -1 (-5025 5350)(-5925 5350);
FORCEPROP 2 LAST SIG_NAME SVID_PVDDCR_CPU0_P0_SVTO_R
J 0
(-5710 5360);
DISPLAY 0.489362 (-5710 5360);
FORCEPROP 2 LASTPROP $XRERR UNIQUE?
J 0
(-5950 5360);
DISPLAY 0.638298 (-5950 5360);
PAINT MONO (-5950 5360);
DISPLAY INVISIBLE (-5950 5360);
WIRE 16 -1 (-5025 5200)(-5925 5200);
FORCEPROP 2 LAST SIG_NAME SVID_PVDDCR_CPU0_P0_SVTI_R
J 0
(-5710 5210);
DISPLAY 0.489362 (-5710 5210);
FORCEPROP 2 LASTPROP $XRERR UNIQUE?
J 0
(-5950 5210);
DISPLAY 0.638298 (-5950 5210);
PAINT MONO (-5950 5210);
DISPLAY INVISIBLE (-5950 5210);
WIRE 16 -1 (-6700 4800)(-6175 4800);
FORCEPROP 2 LAST SIG_NAME SMB_SCM_6_R3_SDA
J 0
(-6710 4810);
DISPLAY 0.489362 (-6710 4810);
WIRE 16 -1 (-6175 4800)(-6025 4800);
WIRE 16 -1 (-6175 4375)(-6175 4800);
WIRE 16 -1 (-6250 4375)(-6175 4375);
WIRE 16 -1 (-6700 4950)(-6225 4950);
FORCEPROP 2 LAST SIG_NAME SMB_SCM_6_R3_SCL
J 0
(-6710 4960);
DISPLAY 0.489362 (-6710 4960);
WIRE 16 -1 (-6225 4950)(-6025 4950);
WIRE 16 -1 (-6225 4475)(-6225 4950);
WIRE 16 -1 (-6250 4475)(-6225 4475);
WIRE 16 -1 (-8675 1425)(-9075 1425);
FORCEPROP 2 LAST SIG_NAME PVDDCR_SOC_P0_EN
J 2
(-8735 1435);
DISPLAY 0.489362 (-8735 1435);
WIRE 16 -1 (-6000 5950)(-6575 5950);
FORCEPROP 2 LAST SIG_NAME PVDDCR_CPU0_P0_EN
J 2
(-6185 5960);
DISPLAY 0.489362 (-6185 5960);
WIRE 16 -1 (-6000 6100)(-6575 6100);
FORCEPROP 2 LAST SIG_NAME PWRGD_PVDDCR_CPU0_P0
J 2
(-6110 6110);
DISPLAY 0.489362 (-6110 6110);
WIRE 16 -1 (-3675 3000)(-2850 3000);
FORCEPROP 2 LAST SIG_NAME NC_PVDDCR_CPU0_P0_PWM8
J 2
(-3085 3010);
DISPLAY 0.489362 (-3085 3010);
FORCEPROP 2 LASTPROP $XRERR UNIQUE?
J 0
(-2820 3000);
DISPLAY 0.638298 (-2820 3000);
PAINT MONO (-2820 3000);
DISPLAY INVISIBLE (-2820 3000);
WIRE 16 -1 (-6425 1000)(-7025 1000);
FORCEPROP 2 LAST SIG_NAME PWRGD_PVDDCR_SOC_P0
J 2
(-6560 1010);
DISPLAY 0.489362 (-6560 1010);
WIRE 17 273 (-8000 3200)(-7150 3200);
WIRE 17 273 (-8000 3200)(-8000 2390);
WIRE 17 273 (-7150 3200)(-7150 2390);
WIRE 17 273 (-8000 2390)(-7150 2390);
WIRE 16 -1 (-6025 4650)(-6750 4650);
FORCEPROP 2 LAST SIG_NAME PVDDCR_CPU0_P0_PMALERT
J 0
(-6710 4660);
DISPLAY 0.489362 (-6710 4660);
WIRE 16 -1 (-3675 5000)(-2850 5000);
FORCEPROP 2 LAST SIG_NAME PVDDCR_CPU0_P0_IMON1
J 2
(-3060 5010);
DISPLAY 0.489362 (-3060 5010);
WIRE 16 -1 (-3675 4800)(-2850 4800);
FORCEPROP 2 LAST SIG_NAME PVDDCR_CPU0_P0_PWM2
J 2
(-3085 4810);
DISPLAY 0.489362 (-3085 4810);
WIRE 16 -1 (-3675 4700)(-2850 4700);
FORCEPROP 2 LAST SIG_NAME PVDDCR_CPU0_P0_IMON2
J 2
(-3060 4710);
DISPLAY 0.489362 (-3060 4710);
WIRE 16 -1 (-7975 5875)(-7975 5350);
WIRE 16 -1 (-6125 5350)(-7975 5350);
FORCEPROP 2 LAST SIG_NAME SVID_PVDDCR_CPU0_P0_SVTO
J 0
(-7010 5360);
DISPLAY 0.489362 (-7010 5360);
WIRE 16 -1 (-7975 5350)(-8050 5350);
WIRE 16 -1 (-8050 5125)(-8050 5350);
WIRE 16 -1 (-8050 5350)(-8275 5350);
WIRE 16 -1 (-8275 5350)(-8275 5125);
WIRE 16 -1 (-8800 5350)(-8275 5350);
WIRE 16 -1 (-5825 4950)(-5025 4950);
FORCEPROP 2 LAST SIG_NAME PVDDCR_CPU0_P0_PMSCL_R
J 2
(-5110 4960);
DISPLAY 0.489362 (-5110 4960);
FORCEPROP 2 LASTPROP $XRERR UNIQUE?
J 0
(-5350 4960);
DISPLAY 0.638298 (-5350 4960);
PAINT MONO (-5350 4960);
DISPLAY INVISIBLE (-5350 4960);
WIRE 16 -1 (-5825 4650)(-5025 4650);
FORCEPROP 2 LAST SIG_NAME PVDDCR_CPU0_P0_PMALERT_R
J 2
(-5110 4660);
DISPLAY 0.489362 (-5110 4660);
FORCEPROP 2 LASTPROP $XRERR UNIQUE?
J 0
(-5350 4660);
DISPLAY 0.638298 (-5350 4660);
PAINT MONO (-5350 4660);
DISPLAY INVISIBLE (-5350 4660);
WIRE 16 -1 (-5825 4800)(-5025 4800);
FORCEPROP 2 LAST SIG_NAME PVDDCR_CPU0_P0_PMSDA_R
J 2
(-5110 4810);
DISPLAY 0.489362 (-5110 4810);
FORCEPROP 2 LASTPROP $XRERR UNIQUE?
J 0
(-5350 4810);
DISPLAY 0.638298 (-5350 4810);
PAINT MONO (-5350 4810);
DISPLAY INVISIBLE (-5350 4810);
WIRE 16 -1 (-5875 2250)(-5775 2250);
WIRE 16 -1 (-5025 2250)(-5775 2250);
FORCEPROP 2 LAST SIG_NAME PVDDCR_CPU0_P0_RESET_N_R
J 0
(-5710 2260);
DISPLAY 0.489362 (-5710 2260);
FORCEPROP 2 LASTPROP $XRERR UNIQUE?
J 0
(-5950 2260);
DISPLAY 0.638298 (-5950 2260);
PAINT MONO (-5950 2260);
DISPLAY INVISIBLE (-5950 2260);
WIRE 16 -1 (-5775 2400)(-5775 2250);
WIRE 16 -1 (-6025 2400)(-5775 2400);
WIRE 16 -1 (-8325 5875)(-8325 5200);
WIRE 16 -1 (-6125 5200)(-8325 5200);
FORCEPROP 2 LAST SIG_NAME SVID_PVDDCR_CPU0_P0_SVTI
J 0
(-7010 5225);
DISPLAY 0.489362 (-7010 5225);
FORCEPROP 2 LASTPROP $XRERR UNIQUE?
J 0
(-7250 5225);
DISPLAY 0.638298 (-7250 5225);
PAINT MONO (-7250 5225);
DISPLAY INVISIBLE (-7250 5225);
WIRE 16 -1 (-8525 5200)(-8325 5200);
WIRE 16 -1 (-8525 5200)(-8525 5125);
WIRE 16 -1 (-7925 1425)(-8175 1425);
FORCEPROP 2 LAST SIG_NAME PVDDCR_SOC_P0_EN_RC
J 2
(-7960 1435);
DISPLAY 0.489362 (-7960 1435);
FORCEPROP 2 LASTPROP $XRERR UNIQUE?
J 0
(-8200 1435);
DISPLAY 0.638298 (-8200 1435);
PAINT MONO (-8200 1435);
DISPLAY INVISIBLE (-8200 1435);
WIRE 16 -1 (-8175 1300)(-8175 1425);
WIRE 16 -1 (-8175 1425)(-8475 1425);
WIRE 16 -1 (-7775 1925)(-7775 1850);
WIRE 16 -1 (-7400 1850)(-7775 1850);
FORCEPROP 2 LAST SIG_NAME PVDDCR_SOC_P0_EN_GD
J 2
(-7310 1800);
DISPLAY 0.489362 (-7310 1800);
FORCEPROP 2 LASTPROP $XRERR UNIQUE?
J 0
(-7550 1800);
DISPLAY 0.638298 (-7550 1800);
PAINT MONO (-7550 1800);
DISPLAY INVISIBLE (-7550 1800);
WIRE 16 -1 (-7775 1625)(-7775 1850);
WIRE 16 -1 (-6650 2250)(-6075 2250);
FORCEPROP 2 LAST SIG_NAME PVDDCR_CPU0_P0_RESET_N
J 0
(-6635 2260);
DISPLAY 0.489362 (-6635 2260);
WIRE 16 -1 (-6650 2100)(-6075 2100);
FORCEPROP 2 LAST SIG_NAME PVDDCR_CPU0_P0_OCP_N
J 0
(-6635 2110);
DISPLAY 0.489362 (-6635 2110);
WIRE 16 -1 (-5875 2100)(-5175 2100);
FORCEPROP 2 LAST SIG_NAME PVDDCR_CPU0_P0_OCP_N_R
J 0
(-5685 2110);
DISPLAY 0.489362 (-5685 2110);
FORCEPROP 2 LASTPROP $XRERR UNIQUE?
J 0
(-5925 2110);
DISPLAY 0.638298 (-5925 2110);
PAINT MONO (-5925 2110);
DISPLAY INVISIBLE (-5925 2110);
WIRE 16 -1 (-5025 2100)(-5175 2100);
WIRE 16 -1 (-5175 1975)(-5175 2100);
WIRE 16 -1 (-5325 1975)(-5175 1975);
WIRE 16 -1 (-5850 2950)(-5675 2950);
WIRE 16 -1 (-5675 2950)(-5025 2950);
FORCEPROP 2 LAST SIG_NAME VSENSE_PVDDCR_SOC_P0_VSEN1
J 2
(-5135 2960);
DISPLAY 0.489362 (-5135 2960);
FORCEPROP 2 LASTPROP $XRERR UNIQUE?
J 0
(-5375 2960);
DISPLAY 0.638298 (-5375 2960);
PAINT MONO (-5375 2960);
DISPLAY INVISIBLE (-5375 2960);
WIRE 16 -1 (-5675 2925)(-5675 2950);
WIRE 16 -1 (-3100 900)(-3375 900);
FORCEPROP 2 LAST SIG_NAME PVDDCR_CPU0_P0_TEMP0
J 2
(-3085 910);
DISPLAY 0.489362 (-3085 910);
WIRE 16 -1 (-3375 800)(-3375 900);
WIRE 16 -1 (-3375 900)(-3675 900);
WIRE 16 -1 (-3675 1800)(-2850 1800);
FORCEPROP 2 LAST SIG_NAME PVDDCR_SOC_P0_PWM1
J 2
(-3075 1810);
DISPLAY 0.489362 (-3075 1810);
WIRE 16 -1 (-3675 2000)(-2850 2000);
FORCEPROP 2 LAST SIG_NAME PVDDCR_SOC_P0_IMON2
J 2
(-3075 2010);
DISPLAY 0.489362 (-3075 2010);
WIRE 16 -1 (-3675 3300)(-2850 3300);
FORCEPROP 2 LAST SIG_NAME NC_PVDDCR_CPU0_P0_PWM7
J 2
(-3085 3310);
DISPLAY 0.489362 (-3085 3310);
FORCEPROP 2 LASTPROP $XRERR UNIQUE?
J 0
(-2820 3300);
DISPLAY 0.638298 (-2820 3300);
PAINT MONO (-2820 3300);
DISPLAY INVISIBLE (-2820 3300);
WIRE 16 -1 (-3675 2900)(-3025 2900);
FORCEPROP 2 LAST SIG_NAME NC_PVDDCR_CPU0_P0_IMON8
J 2
(-3060 2910);
DISPLAY 0.489362 (-3060 2910);
FORCEPROP 2 LASTPROP $XRERR UNIQUE?
J 0
(-3300 2910);
DISPLAY 0.638298 (-3300 2910);
PAINT MONO (-3300 2910);
DISPLAY INVISIBLE (-3300 2910);
WIRE 16 -1 (-3675 2100)(-2850 2100);
FORCEPROP 2 LAST SIG_NAME PVDDCR_SOC_P0_PWM2
J 2
(-3075 2110);
DISPLAY 0.489362 (-3075 2110);
WIRE 16 -1 (-3675 3800)(-2850 3800);
FORCEPROP 2 LAST SIG_NAME PVDDCR_CPU0_P0_IMON5
J 2
(-3060 3810);
DISPLAY 0.489362 (-3060 3810);
WIRE 16 -1 (-3675 3900)(-2850 3900);
FORCEPROP 2 LAST SIG_NAME PVDDCR_CPU0_P0_PWM5
J 2
(-3085 3910);
DISPLAY 0.489362 (-3085 3910);
WIRE 16 -1 (-2925 5800)(-3200 5800);
WIRE 16 -1 (-2925 5800)(-2525 5800);
FORCEPROP 2 LAST SIG_NAME PVDDCR_CPU0_P0_VCCS
J 2
(-2910 5810);
DISPLAY 0.489362 (-2910 5810);
WIRE 16 -1 (-2925 5750)(-2925 5800);
WIRE 16 -1 (-3200 5800)(-3200 5750);
WIRE 16 -1 (-3200 5800)(-3675 5800);
WIRE 16 -1 (-3675 5100)(-2850 5100);
FORCEPROP 2 LAST SIG_NAME PVDDCR_CPU0_P0_PWM1
J 2
(-3085 5110);
DISPLAY 0.489362 (-3085 5110);
WIRE 16 -1 (-3675 4500)(-2850 4500);
FORCEPROP 2 LAST SIG_NAME PVDDCR_CPU0_P0_PWM3
J 2
(-3085 4510);
DISPLAY 0.489362 (-3085 4510);
WIRE 16 -1 (-3675 4400)(-2850 4400);
FORCEPROP 2 LAST SIG_NAME PVDDCR_CPU0_P0_IMON3
J 2
(-3060 4410);
DISPLAY 0.489362 (-3060 4410);
WIRE 16 -1 (-3675 4200)(-2850 4200);
FORCEPROP 2 LAST SIG_NAME PVDDCR_CPU0_P0_PWM4
J 2
(-3085 4210);
DISPLAY 0.489362 (-3085 4210);
WIRE 16 -1 (-3675 4100)(-2850 4100);
FORCEPROP 2 LAST SIG_NAME PVDDCR_CPU0_P0_IMON4
J 2
(-3060 4110);
DISPLAY 0.489362 (-3060 4110);
WIRE 16 -1 (-2900 6225)(-2900 6275);
WIRE 16 -1 (-2575 6275)(-2900 6275);
WIRE 16 -1 (-3200 6275)(-2900 6275);
FORCEPROP 2 LAST SIG_NAME PVDDCR_CPU0_P0_VCC
J 2
(-2960 6300);
DISPLAY 0.489362 (-2960 6300);
FORCEPROP 2 LASTPROP $XRERR UNIQUE?
J 0
(-3200 6300);
DISPLAY 0.638298 (-3200 6300);
PAINT MONO (-3200 6300);
DISPLAY INVISIBLE (-3200 6300);
WIRE 16 -1 (-3450 6275)(-3200 6275);
WIRE 16 -1 (-3200 6275)(-3200 6225);
WIRE 16 -1 (-3450 6100)(-3450 6275);
WIRE 16 -1 (-3675 6100)(-3450 6100);
WIRE 16 -1 (-5650 750)(-5025 750);
FORCEPROP 2 LAST SIG_NAME PVDDCR_CPU0_P0_VMON
J 2
(-5160 760);
DISPLAY 0.489362 (-5160 760);
FORCEPROP 2 LASTPROP $XRERR UNIQUE?
J 0
(-5400 760);
DISPLAY 0.638298 (-5400 760);
PAINT MONO (-5400 760);
DISPLAY INVISIBLE (-5400 760);
WIRE 16 -1 (-5650 825)(-5650 750);
WIRE 16 -1 (-5650 825)(-6475 825);
WIRE 16 -1 (-6475 725)(-6475 825);
WIRE 16 -1 (-6475 825)(-6950 825);
WIRE 16 -1 (-7150 825)(-6950 825);
WIRE 16 -1 (-6950 725)(-6950 825);
WIRE 16 -1 (-5100 500)(-5100 550);
WIRE 16 -1 (-5100 550)(-5025 550);
WIRE 16 -1 (-7100 2175)(-7775 2175);
WIRE 16 -1 (-7100 2150)(-7100 2175);
WIRE 16 -1 (-7775 2175)(-7775 2200);
WIRE 16 -1 (-7775 2125)(-7775 2175);
WIRE 16 -1 (-7400 6175)(-7675 6175);
WIRE 16 -1 (-7400 6175)(-7400 6075);
WIRE 16 -1 (-7675 6075)(-7675 6175);
WIRE 16 -1 (-7675 6175)(-7975 6175);
WIRE 16 -1 (-7975 6075)(-7975 6175);
WIRE 16 -1 (-7975 6175)(-8325 6175);
WIRE 16 -1 (-8325 6225)(-8325 6175);
WIRE 16 -1 (-8325 6075)(-8325 6175);
WIRE 16 -1 (-5000 5800)(-5000 5825);
WIRE 16 -1 (-5000 5825)(-5125 5825);
WIRE 16 -1 (-7775 1250)(-7100 1250);
WIRE 16 -1 (-7775 1250)(-7775 1325);
WIRE 16 -1 (-7100 1225)(-7100 1250);
WIRE 16 -1 (-7100 1275)(-7100 1250);
WIRE 16 -1 (-6525 6450)(-6525 6375);
WIRE 16 -1 (-6525 6375)(-6225 6375);
WIRE 16 -1 (-5000 6350)(-5000 6375);
WIRE 16 -1 (-5000 6375)(-5150 6375);
WIRE 16 -1 (-2575 2525)(-2575 2600);
WIRE 16 -1 (-2575 2600)(-2825 2600);
WIRE 16 -1 (-2575 3100)(-2575 3200);
WIRE 16 -1 (-2575 3200)(-2825 3200);
WIRE 16 -1 (-2575 2800)(-2575 2900);
WIRE 16 -1 (-2575 2900)(-2825 2900);
WIRE 16 -1 (-6575 2475)(-6575 2400);
WIRE 16 -1 (-6575 2400)(-6225 2400);
WIRE 16 -1 (-6075 1725)(-6275 1725);
WIRE 16 -1 (-5775 1725)(-6075 1725);
WIRE 16 -1 (-6075 1725)(-6075 1850);
WIRE 16 -1 (-6275 1725)(-6275 1750);
WIRE 16 -1 (-5025 1850)(-6075 1850);
WIRE 16 -1 (-6075 1975)(-6075 1850);
WIRE 16 -1 (-5525 1975)(-6075 1975);
WIRE 16 -1 (-2050 6325)(-2050 6275);
WIRE 16 -1 (-2050 6275)(-2375 6275);
WIRE 16 -1 (-6175 4200)(-6175 4275);
WIRE 16 -1 (-6175 4275)(-6250 4275);
WIRE 16 -1 (-5325 1175)(-5325 1250);
WIRE 16 -1 (-5325 1250)(-5550 1250);
WIRE 16 -1 (-6600 1350)(-6600 1250);
WIRE 16 -1 (-6600 1250)(-6425 1250);
WIRE 16 -1 (-7550 900)(-7550 825);
WIRE 16 -1 (-7550 825)(-7350 825);
WIRE 16 -1 (-6175 675)(-6175 650);
WIRE 16 -1 (-6175 650)(-6075 650);
DOT 1 (-6050 1250);
DOT 1 (-6175 4800);
DOT 1 (-6225 4950);
DOT 1 (-6075 1725);
DOT 1 (-6475 825);
DOT 1 (-5175 2100);
DOT 1 (-5300 650);
DOT 1 (-3375 900);
DOT 1 (-2750 1200);
DOT 1 (-6075 1850);
DOT 1 (-5675 2950);
DOT 1 (-5750 4050);
DOT 1 (-3200 5800);
DOT 1 (-7100 1250);
DOT 1 (-6950 825);
DOT 1 (-7775 1850);
DOT 1 (-6050 1000);
DOT 1 (-7675 5500);
DOT 1 (-7400 5650);
DOT 1 (-8325 5200);
DOT 1 (-8275 5350);
DOT 1 (-8325 6175);
DOT 1 (-7100 1500);
DOT 1 (-7775 2175);
DOT 1 (-7050 2700);
DOT 1 (-7050 2950);
DOT 1 (-7050 3800);
DOT 1 (-7050 4050);
DOT 1 (-5775 2250);
DOT 1 (-5675 2700);
DOT 1 (-7975 5350);
DOT 1 (-8050 5350);
DOT 1 (-7825 5500);
DOT 1 (-7600 5650);
DOT 1 (-7975 6175);
DOT 1 (-7675 6175);
DOT 1 (-5625 6100);
DOT 1 (-5625 6375);
DOT 1 (-2925 5800);
DOT 1 (-3200 6275);
DOT 1 (-2900 6275);
DOT 1 (-5675 650);
DOT 1 (-5750 3800);
DOT 1 (-8175 1425);
DOT 1 (-5625 5950);
FORCENOTE
PR292=CS37502FB05
(-1975 2050) 0;
DISPLAY LEFT (-1975 2050);
DISPLAY 1.021277 (-1975 2050);
PAINT WHITE (-1975 2050);
FORCENOTE
PR5=CS00002JB38
(-1975 1975) 0;
DISPLAY LEFT (-1975 1975);
DISPLAY 1.021277 (-1975 1975);
PAINT WHITE (-1975 1975);
FORCENOTE
PC469,PC472=TMP_QCH31004KB17
(-1975 1675) 0;
DISPLAY LEFT (-1975 1675);
DISPLAY 1.021277 (-1975 1675);
PAINT WHITE (-1975 1675);
FORCENOTE
PU42=AR0T6GPV001
(-1975 3025) 0;
DISPLAY LEFT (-1975 3025);
DISPLAY 1.021277 (-1975 3025);
PAINT WHITE (-1975 3025);
FORCENOTE
2ND SOURCE:INFENEON BOM
(-1975 3100) 0;
DISPLAY LEFT (-1975 3100);
DISPLAY 1.021277 (-1975 3100);
PAINT WHITE (-1975 3100);
FORCENOTE
PU42=AR0T6GPV005/RAA229620GNP#HA0
(-1975 3250) 0;
DISPLAY LEFT (-1975 3250);
DISPLAY 1.021277 (-1975 3250);
PAINT WHITE (-1975 3250);
FORCENOTE
MAIN SOURCE:RENESAS BOM
(-1975 3325) 0;
DISPLAY LEFT (-1975 3325);
DISPLAY 1.021277 (-1975 3325);
PAINT WHITE (-1975 3325);
FORCENOTE
BOM NOTE
(-1975 3425) 0;
DISPLAY LEFT (-1975 3425);
DISPLAY 1.595745 (-1975 3425);
PAINT WHITE (-1975 3425);
FORCENOTE
0/681 OHM
(-8300 425) 0;
DISPLAY LEFT (-8300 425);
DISPLAY 0.638298 (-8300 425);
PAINT WHITE (-8300 425);
FORCENOTE
/681 OHM
(-8300 350) 0;
DISPLAY LEFT (-8300 350);
DISPLAY 0.638298 (-8300 350);
PAINT WHITE (-8300 350);
FORCENOTE
VR
(-9100 525) 0;
DISPLAY LEFT (-9100 525);
DISPLAY 0.808511 (-9100 525);
PAINT WHITE (-9100 525);
FORCENOTE
RENESAS
(-9100 425) 0;
DISPLAY LEFT (-9100 425);
DISPLAY 0.638298 (-9100 425);
PAINT WHITE (-9100 425);
FORCENOTE
TRACE WIDTH = 10MIL
(-7925 2500) 0;
DISPLAY LEFT (-7925 2500);
DISPLAY 0.808511 (-7925 2500);
PAINT WHITE (-7925 2500);
FORCENOTE
DIFFERENTIAL PAIR
(-7925 2575) 0;
DISPLAY LEFT (-7925 2575);
DISPLAY 0.808511 (-7925 2575);
PAINT WHITE (-7925 2575);
FORCENOTE
SVI3 ADDRESS=PORT0 (0X2)
(-1650 4100) 0;
DISPLAY LEFT (-1650 4100);
DISPLAY 0.936170 (-1650 4100);
PAINT WHITE (-1650 4100);
FORCENOTE
EFFICIENCY > 90% @TDC
(-1650 4175) 0;
DISPLAY LEFT (-1650 4175);
DISPLAY 0.936170 (-1650 4175);
PAINT WHITE (-1650 4175);
FORCENOTE
WORK FREQUENCY=600KHZ
(-1650 4250) 0;
DISPLAY LEFT (-1650 4250);
DISPLAY 0.936170 (-1650 4250);
PAINT WHITE (-1650 4250);
FORCENOTE
PR314=CS37502FB05
(-1975 1900) 0;
DISPLAY LEFT (-1975 1900);
DISPLAY 1.021277 (-1975 1900);
PAINT WHITE (-1975 1900);
FORCENOTE
PC7=TMP_QCH21006JB10
(-1975 1825) 0;
DISPLAY LEFT (-1975 1825);
DISPLAY 1.021277 (-1975 1825);
PAINT WHITE (-1975 1825);
FORCENOTE
PR599=CS24992FB07
(-1975 1750) 0;
DISPLAY LEFT (-1975 1750);
DISPLAY 1.021277 (-1975 1750);
PAINT WHITE (-1975 1750);
FORCENOTE
TRACE WIDTH = 10MIL
(-7950 3600) 0;
DISPLAY LEFT (-7950 3600);
DISPLAY 0.808511 (-7950 3600);
PAINT WHITE (-7950 3600);
FORCENOTE
TRACE SPACING = 5MIL
(-7950 3525) 0;
DISPLAY LEFT (-7950 3525);
DISPLAY 0.808511 (-7950 3525);
PAINT WHITE (-7950 3525);
FORCENOTE
DIFFERENTIAL PAIR
(-7950 3675) 0;
DISPLAY LEFT (-7950 3675);
DISPLAY 0.808511 (-7950 3675);
PAINT WHITE (-7950 3675);
FORCENOTE
LOAD RELEASE=200A
(-1650 5675) 0;
DISPLAY LEFT (-1650 5675);
DISPLAY 0.936170 (-1650 5675);
PAINT WHITE (-1650 5675);
FORCENOTE
DC=+/-20MV
(-1650 4850) 0;
DISPLAY LEFT (-1650 4850);
DISPLAY 0.936170 (-1650 4850);
PAINT WHITE (-1650 4850);
FORCENOTE
LOAD RELEASE=95A
(-1650 4325) 0;
DISPLAY LEFT (-1650 4325);
DISPLAY 0.936170 (-1650 4325);
PAINT WHITE (-1650 4325);
FORCENOTE
LOAD STEP=45A
(-1650 4400) 0;
DISPLAY LEFT (-1650 4400);
DISPLAY 0.936170 (-1650 4400);
PAINT WHITE (-1650 4400);
FORCENOTE
OCP=156A (EDC*1.2)
(-1650 4475) 0;
DISPLAY LEFT (-1650 4475);
DISPLAY 0.936170 (-1650 4475);
PAINT WHITE (-1650 4475);
FORCENOTE
MIN AC=VID-150MV
(-1650 4700) 0;
DISPLAY LEFT (-1650 4700);
DISPLAY 0.936170 (-1650 4700);
PAINT WHITE (-1650 4700);
FORCENOTE
RIPPLE=+/-10MV
(-1650 4925) 0;
DISPLAY LEFT (-1650 4925);
DISPLAY 0.936170 (-1650 4925);
PAINT WHITE (-1650 4925);
FORCENOTE
LOAD STEP=200A
(-1650 5750) 0;
DISPLAY LEFT (-1650 5750);
DISPLAY 0.936170 (-1650 5750);
PAINT WHITE (-1650 5750);
FORCENOTE
EDC=230A
(-1650 5900) 0;
DISPLAY LEFT (-1650 5900);
DISPLAY 0.936170 (-1650 5900);
PAINT WHITE (-1650 5900);
FORCENOTE
TDC=175A
(-1650 5975) 0;
DISPLAY LEFT (-1650 5975);
DISPLAY 0.936170 (-1650 5975);
PAINT WHITE (-1650 5975);
FORCENOTE
EDC=130A
(-1650 4550) 0;
DISPLAY LEFT (-1650 4550);
DISPLAY 0.936170 (-1650 4550);
PAINT WHITE (-1650 4550);
FORCENOTE
TDC=105A
(-1650 4625) 0;
DISPLAY LEFT (-1650 4625);
DISPLAY 0.936170 (-1650 4625);
PAINT WHITE (-1650 4625);
FORCENOTE
OCP=276A (EDC*1.2)
(-1650 5825) 0;
DISPLAY LEFT (-1650 5825);
DISPLAY 0.936170 (-1650 5825);
PAINT WHITE (-1650 5825);
FORCENOTE
MIN AC=VID-EDC*LL-110MV
(-1650 6050) 0;
DISPLAY LEFT (-1650 6050);
DISPLAY 0.936170 (-1650 6050);
PAINT WHITE (-1650 6050);
FORCENOTE
LOAD-LINE=0.4MOHM
(-1650 5600) 0;
DISPLAY LEFT (-1650 5600);
DISPLAY 0.936170 (-1650 5600);
PAINT WHITE (-1650 5600);
FORCENOTE
MAX AC=+200MV
(-1650 6125) 0;
DISPLAY LEFT (-1650 6125);
DISPLAY 0.936170 (-1650 6125);
PAINT WHITE (-1650 6125);
FORCENOTE
VID=0.55-2V
(-1650 6350) 0;
DISPLAY LEFT (-1650 6350);
DISPLAY 0.936170 (-1650 6350);
PAINT WHITE (-1650 6350);
FORCENOTE
DC=+/-20MV
(-1650 6200) 0;
DISPLAY LEFT (-1650 6200);
DISPLAY 0.936170 (-1650 6200);
PAINT WHITE (-1650 6200);
FORCENOTE
RIPPLE=+/-10MV
(-1650 6275) 0;
DISPLAY LEFT (-1650 6275);
DISPLAY 0.936170 (-1650 6275);
PAINT WHITE (-1650 6275);
FORCENOTE
PVDDCR_CPU0_P0 SPECFICATION
(-1650 6497) 0;
DISPLAY LEFT (-1650 6497);
DISPLAY 1.170213 (-1650 6497);
PAINT WHITE (-1650 6497);
FORCENOTE
TRACE SPACING = 5MIL
(-7925 2425) 0;
DISPLAY LEFT (-7925 2425);
DISPLAY 0.808511 (-7925 2425);
PAINT WHITE (-7925 2425);
FORCENOTE
MAX AC=VID+150MV
(-1650 4775) 0;
DISPLAY LEFT (-1650 4775);
DISPLAY 0.936170 (-1650 4775);
PAINT WHITE (-1650 4775);
FORCENOTE
VID=0.75-1.2V
(-1650 5000) 0;
DISPLAY LEFT (-1650 5000);
DISPLAY 0.936170 (-1650 5000);
PAINT WHITE (-1650 5000);
FORCENOTE
WORK FREQUENCY=600KHZ
(-1650 5525) 0;
DISPLAY LEFT (-1650 5525);
DISPLAY 0.936170 (-1650 5525);
PAINT WHITE (-1650 5525);
FORCENOTE
EFFICIENCY > 90% @TDC
(-1650 5450) 0;
DISPLAY LEFT (-1650 5450);
DISPLAY 0.936170 (-1650 5450);
PAINT WHITE (-1650 5450);
FORCENOTE
SVI3 ADDRESS=PORT0 (0X1)
(-1650 5375) 0;
DISPLAY LEFT (-1650 5375);
DISPLAY 0.936170 (-1650 5375);
PAINT WHITE (-1650 5375);
FORCENOTE
CONFIG/R
(-8300 525) 0;
DISPLAY LEFT (-8300 525);
DISPLAY 0.808511 (-8300 525);
PAINT WHITE (-8300 525);
FORCENOTE
/75K OHM
(-8300 275) 0;
DISPLAY LEFT (-8300 275);
DISPLAY 0.638298 (-8300 275);
PAINT WHITE (-8300 275);
FORCENOTE
INFINEON
(-9100 350) 0;
DISPLAY LEFT (-9100 350);
DISPLAY 0.638298 (-9100 350);
PAINT WHITE (-9100 350);
FORCENOTE
MPS
(-9100 275) 0;
DISPLAY LEFT (-9100 275);
DISPLAY 0.638298 (-9100 275);
PAINT WHITE (-9100 275);
FORCENOTE
0X61
(-8650 425) 0;
DISPLAY LEFT (-8650 425);
DISPLAY 0.638298 (-8650 425);
PAINT WHITE (-8650 425);
FORCENOTE
0X4F
(-8650 275) 0;
DISPLAY LEFT (-8650 275);
DISPLAY 0.638298 (-8650 275);
PAINT WHITE (-8650 275);
FORCENOTE
0X4F
(-8650 350) 0;
DISPLAY LEFT (-8650 350);
DISPLAY 0.638298 (-8650 350);
PAINT WHITE (-8650 350);
FORCENOTE
ADDRESS
(-8650 525) 0;
DISPLAY LEFT (-8650 525);
DISPLAY 0.808511 (-8650 525);
PAINT WHITE (-8650 525);
FORCENOTE
PMBUS ADDRESS AND CONFIG
(-9200 650) 0;
DISPLAY LEFT (-9200 650);
DISPLAY 1.170213 (-9200 650);
PAINT WHITE (-9200 650);
FORCENOTE
PVDDCR_SOC_P0 SPECFICATION
(-1650 5125) 0;
DISPLAY LEFT (-1650 5125);
DISPLAY 1.276596 (-1650 5125);
PAINT WHITE (-1650 5125);
FORCENOTE
PR290,PC462=EMPTY
(-1975 2125) 0;
DISPLAY LEFT (-1975 2125);
DISPLAY 1.021277 (-1975 2125);
PAINT WHITE (-1975 2125);
FORCENOTE
PR531,PR440,PR441,PC463,PC464=EMPTY
(-1975 2200) 0;
DISPLAY LEFT (-1975 2200);
DISPLAY 1.021277 (-1975 2200);
PAINT WHITE (-1975 2200);
FORCENOTE
PU42=AL002857001
(-1975 2275) 0;
DISPLAY LEFT (-1975 2275);
DISPLAY 1.021277 (-1975 2275);
PAINT WHITE (-1975 2275);
FORCENOTE
3RD SOURCE:MPS BOM
(-1975 2350) 0;
DISPLAY LEFT (-1975 2350);
DISPLAY 1.021277 (-1975 2350);
PAINT WHITE (-1975 2350);
FORCENOTE
PR531,PR440,PR441=EMPTY
(-1975 2500) 0;
DISPLAY LEFT (-1975 2500);
DISPLAY 1.021277 (-1975 2500);
PAINT WHITE (-1975 2500);
FORCENOTE
PR5=CS21002FB24
(-1975 2575) 0;
DISPLAY LEFT (-1975 2575);
DISPLAY 1.021277 (-1975 2575);
PAINT WHITE (-1975 2575);
FORCENOTE
PR290=CS25362FB15
(-1975 2650) 0;
DISPLAY LEFT (-1975 2650);
DISPLAY 1.021277 (-1975 2650);
PAINT WHITE (-1975 2650);
FORCENOTE
PC463,PC464=CH12206KB14
(-1975 2725) 0;
DISPLAY LEFT (-1975 2725);
DISPLAY 1.021277 (-1975 2725);
PAINT WHITE (-1975 2725);
FORCENOTE
PR283=CS00002JB38
(-1975 2950) 0;
DISPLAY LEFT (-1975 2950);
DISPLAY 1.021277 (-1975 2950);
PAINT WHITE (-1975 2950);
FORCENOTE
PC472,PC469=CH11006JB00
(-1975 2800) 0;
DISPLAY LEFT (-1975 2800);
DISPLAY 1.021277 (-1975 2800);
PAINT WHITE (-1975 2800);
FORCENOTE
PC470=CH5103KEB01
(-1975 2875) 0;
DISPLAY LEFT (-1975 2875);
DISPLAY 1.021277 (-1975 2875);
PAINT WHITE (-1975 2875);
FORCENOTE
PC462=CH3104J1B00
(-1975 2425) 0;
DISPLAY LEFT (-1975 2425);
DISPLAY 1.021277 (-1975 2425);
PAINT WHITE (-1975 2425);
QUIT
